FILE_TYPE = MACRO_DRAWING;
SET COLOR_WIRE YELLOW;
SET COLOR_PROP MONO;
SET COLOR_DOT WHITE;
SET COLOR_ARC YELLOW;
SET COLOR_BODY GREEN;
SET COLOR_NOTE MONO;
SET PROP_DISPLAY VALUE;
SET PAGE_NUMBER P209;
FORCEADD OFFPAGE..1
(-7625 1575);
FORCEPROP 2 LAST $XR0 206 
J 0
(-7877 1575);
DISPLAY 0.638298 (-7877 1575);
PAINT MONO (-7877 1575);
FORCEPROP 2 LAST CDS_LIB mstr_standard
J 0
(-7625 1575);
PAINT ORANGE (-7625 1575);
DISPLAY INVISIBLE (-7625 1575);
FORCEPROP 1 LAST OFFPAGE TRUE
J 0
(-7300 1450);
DISPLAY 0.893617 (-7300 1450);
PAINT GREEN (-7300 1450);
DISPLAY INVISIBLE (-7300 1450);
FORCEPROP 1 LAST COMMENT_BODY TRUE
J 0
(-7500 1475);
DISPLAY 0.893617 (-7500 1475);
PAINT GREEN (-7500 1475);
DISPLAY INVISIBLE (-7500 1475);
FORCEPROP 2 LAST PATH I1
J 0
(-7860 1610);
DISPLAY 1.021277 (-7860 1610);
PAINT ORANGE (-7860 1610);
DISPLAY INVISIBLE (-7860 1610);
FORCEPROP 2 LAST BOM_COST PROC_VRD_VCCIN_CPU0
J 0
(-7825 1625);
PAINT MONO (-7825 1625);
DISPLAY INVISIBLE (-7825 1625);
FORCEPROP 2 LAST ROOM PVCCIN_CPU1_VSENSE_VR
J 0
(-8150 1650);
PAINT ORANGE (-8150 1650);
DISPLAY INVISIBLE (-8150 1650);
FORCEADD RES..1
(-5475 1450);
FORCEPROP 1 LAST MATERIAL CHIP
J 0
(-5475 1300);
DISPLAY 0.617021 (-5475 1300);
PAINT SKYBLUE (-5475 1300);
FORCEPROP 1 LAST PART_NUMBER G21497-005
J 0
(-5600 1550);
DISPLAY 0.617021 (-5600 1550);
PAINT BLUE (-5600 1550);
FORCEPROP 1 LASTPIN (-5375 1450) $PN 2
J 0
(-5413 1462);
DISPLAY 0.617021 (-5413 1462);
PAINT GREEN (-5413 1462);
FORCEPROP 1 LAST TOLERANCE 5%
J 0
(-5475 1375);
DISPLAY 0.617021 (-5475 1375);
PAINT SKYBLUE (-5475 1375);
FORCEPROP 1 LAST VALUE 0.0
J 2
(-5500 1375);
DISPLAY 0.617021 (-5500 1375);
PAINT SKYBLUE (-5500 1375);
FORCEPROP 1 LAST LOCATION R1E7
J 0
(-5525 1500);
DISPLAY 0.617021 (-5525 1500);
PAINT AQUA (-5525 1500);
FORCEPROP 1 LASTPIN (-5575 1450) $PN 1
J 0
(-5563 1462);
DISPLAY 0.617021 (-5563 1462);
PAINT GREEN (-5563 1462);
FORCEPROP 1 LAST PACK_TYPE 0402
J 0
(-5600 1250);
DISPLAY 0.617021 (-5600 1250);
PAINT SKYBLUE (-5600 1250);
FORCEPROP 1 LAST WATTAGE 1/16W
J 2
(-5500 1300);
DISPLAY 0.617021 (-5500 1300);
PAINT SKYBLUE (-5500 1300);
FORCEPROP 2 LAST BOM_COST PROC_VRD_VCCIN_CPU0
J 0
(-5600 1600);
PAINT MONO (-5600 1600);
DISPLAY INVISIBLE (-5600 1600);
FORCEPROP 2 LAST CDS_SEC 1
J 0
(-5525 1650);
PAINT MONO (-5525 1650);
DISPLAY INVISIBLE (-5525 1650);
FORCEPROP 2 LAST $SEC 1
J 0
(-5525 1650);
PAINT MONO (-5525 1650);
DISPLAY INVISIBLE (-5525 1650);
FORCEPROP 1 LAST PATH I10
J 0
(-5525 1600);
DISPLAY 0.978723 (-5525 1600);
PAINT WHITE (-5525 1600);
DISPLAY INVISIBLE (-5525 1600);
FORCEPROP 2 LAST ROOM PVCCIN_CPU1_VSENSE_VR
J 0
(-5525 1550);
PAINT ORANGE (-5525 1550);
DISPLAY INVISIBLE (-5525 1550);
FORCEPROP 2 LAST CDS_LIB mstr_discrete
J 0
(-5475 1450);
PAINT ORANGE (-5475 1450);
DISPLAY INVISIBLE (-5475 1450);
FORCEPROP 2 LAST CDS_LOCATION R1E7
J 0
(-5525 1500);
DISPLAY 0.617021 (-5525 1500);
PAINT AQUA (-5525 1500);
DISPLAY INVISIBLE (-5525 1500);
FORCEADD RES..1
(-5500 1900);
FORCEPROP 1 LAST PART_NUMBER G21497-005
J 0
(-5625 2000);
DISPLAY 0.617021 (-5625 2000);
PAINT BLUE (-5625 2000);
FORCEPROP 1 LAST TOLERANCE 5%
J 0
(-5500 1825);
DISPLAY 0.617021 (-5500 1825);
PAINT SKYBLUE (-5500 1825);
FORCEPROP 1 LASTPIN (-5400 1900) $PN 2
J 0
(-5438 1912);
DISPLAY 0.617021 (-5438 1912);
PAINT GREEN (-5438 1912);
FORCEPROP 1 LAST LOCATION R1E6
J 0
(-5550 1950);
DISPLAY 0.617021 (-5550 1950);
PAINT AQUA (-5550 1950);
FORCEPROP 1 LAST VALUE 0.0
J 2
(-5525 1825);
DISPLAY 0.617021 (-5525 1825);
PAINT SKYBLUE (-5525 1825);
FORCEPROP 1 LASTPIN (-5600 1900) $PN 1
J 0
(-5588 1912);
DISPLAY 0.617021 (-5588 1912);
PAINT GREEN (-5588 1912);
FORCEPROP 1 LAST MATERIAL CHIP
J 0
(-5500 1750);
DISPLAY 0.617021 (-5500 1750);
PAINT SKYBLUE (-5500 1750);
FORCEPROP 1 LAST PACK_TYPE 0402
J 0
(-5625 1700);
DISPLAY 0.617021 (-5625 1700);
PAINT SKYBLUE (-5625 1700);
FORCEPROP 1 LAST WATTAGE 1/16W
J 2
(-5525 1750);
DISPLAY 0.617021 (-5525 1750);
PAINT SKYBLUE (-5525 1750);
FORCEPROP 2 LAST BOM_COST PROC_VRD_VCCIN_CPU0
J 0
(-5625 2050);
PAINT MONO (-5625 2050);
DISPLAY INVISIBLE (-5625 2050);
FORCEPROP 2 LAST CDS_SEC 1
J 0
(-5550 2100);
PAINT MONO (-5550 2100);
DISPLAY INVISIBLE (-5550 2100);
FORCEPROP 2 LAST $SEC 1
J 0
(-5550 2100);
PAINT MONO (-5550 2100);
DISPLAY INVISIBLE (-5550 2100);
FORCEPROP 1 LAST PATH I11
J 0
(-5550 2050);
DISPLAY 0.978723 (-5550 2050);
PAINT WHITE (-5550 2050);
DISPLAY INVISIBLE (-5550 2050);
FORCEPROP 2 LAST CDS_LIB mstr_discrete
J 0
(-5500 1900);
PAINT ORANGE (-5500 1900);
DISPLAY INVISIBLE (-5500 1900);
FORCEPROP 2 LAST ROOM PVCCIN_CPU1_VSENSE_VR
J 0
(-5550 2000);
PAINT ORANGE (-5550 2000);
DISPLAY INVISIBLE (-5550 2000);
FORCEPROP 2 LAST CDS_LOCATION R1E6
J 0
(-5550 1950);
DISPLAY 0.617021 (-5550 1950);
PAINT AQUA (-5550 1950);
DISPLAY INVISIBLE (-5550 1950);
FORCEADD GND..1
(-4825 775);
FORCEPROP 3 LASTPIN (-4825 825) SIG_NAME GND\g
J 0
(-4815 835);
DISPLAY 0.659574 (-4815 835);
PAINT MONO (-4815 835);
DISPLAY INVISIBLE (-4815 835);
FORCEPROP 1 LAST VOLTAGE 0
J 0
(-4825 775);
PAINT SKYBLUE (-4825 775);
DISPLAY INVISIBLE (-4825 775);
FORCEPROP 2 LAST CDS_LIB mstr_symbols
J 0
(-4825 775);
PAINT ORANGE (-4825 775);
DISPLAY INVISIBLE (-4825 775);
FORCEPROP 1 LAST SIZE 1B
J 0
(-4750 725);
DISPLAY 0.893617 (-4750 725);
PAINT GREEN (-4750 725);
DISPLAY INVISIBLE (-4750 725);
FORCEPROP 1 LAST BODY_TYPE PLUMBING
J 0
(-4870 732);
DISPLAY 0.340426 (-4870 732);
PAINT GREEN (-4870 732);
DISPLAY INVISIBLE (-4870 732);
FORCEPROP 1 LAST PATH I12
J 0
(-4750 775);
DISPLAY 0.872340 (-4750 775);
PAINT AQUA (-4750 775);
DISPLAY INVISIBLE (-4750 775);
FORCEPROP 1 LAST HDL_POWER GND
J 0
(-4825 925);
DISPLAY 0.893617 (-4825 925);
PAINT GREEN (-4825 925);
DISPLAY INVISIBLE (-4825 925);
FORCEPROP 2 LAST BOM_COST PROC_VRD_VCCIN_CPU0
J 0
(-5200 850);
PAINT MONO (-5200 850);
DISPLAY INVISIBLE (-5200 850);
FORCEPROP 2 LAST ROOM PVCCIN_CPU1_VSENSE_VR
J 0
(-5375 850);
PAINT ORANGE (-5375 850);
DISPLAY INVISIBLE (-5375 850);
FORCEADD OFFPAGE..2
(-4300 1450);
FORCEPROP 2 LAST $XR0 71 
J 0
(-4111 1450);
DISPLAY 0.638298 (-4111 1450);
PAINT MONO (-4111 1450);
FORCEPROP 1 LAST OFFPAGE TRUE
J 0
(-3975 1325);
DISPLAY 0.893617 (-3975 1325);
PAINT GREEN (-3975 1325);
DISPLAY INVISIBLE (-3975 1325);
FORCEPROP 2 LAST BOM_COST PROC_VRD_VCCIN_CPU0
J 0
(-4100 1500);
PAINT MONO (-4100 1500);
DISPLAY INVISIBLE (-4100 1500);
FORCEPROP 2 LAST PATH I13
J 0
(-4110 1485);
DISPLAY 1.021277 (-4110 1485);
PAINT ORANGE (-4110 1485);
DISPLAY INVISIBLE (-4110 1485);
FORCEPROP 2 LAST CDS_LIB mstr_standard
J 0
(-4300 1450);
PAINT ORANGE (-4300 1450);
DISPLAY INVISIBLE (-4300 1450);
FORCEPROP 1 LAST COMMENT_BODY TRUE
J 0
(-4345 1355);
DISPLAY 0.893617 (-4345 1355);
PAINT GREEN (-4345 1355);
DISPLAY INVISIBLE (-4345 1355);
FORCEPROP 2 LAST ROOM PVCCIN_CPU1_VSENSE_VR
J 0
(-4700 1525);
PAINT ORANGE (-4700 1525);
DISPLAY INVISIBLE (-4700 1525);
FORCEADD OFFPAGE..2
(-4300 1900);
FORCEPROP 2 LAST $XR0 71 
J 0
(-4111 1900);
DISPLAY 0.638298 (-4111 1900);
PAINT MONO (-4111 1900);
FORCEPROP 2 LAST BOM_COST PROC_VRD_VCCIN_CPU0
J 0
(-3975 1950);
PAINT MONO (-3975 1950);
DISPLAY INVISIBLE (-3975 1950);
FORCEPROP 1 LAST OFFPAGE TRUE
J 0
(-3975 1775);
DISPLAY 0.893617 (-3975 1775);
PAINT GREEN (-3975 1775);
DISPLAY INVISIBLE (-3975 1775);
FORCEPROP 2 LAST PATH I14
J 0
(-4110 1935);
DISPLAY 1.021277 (-4110 1935);
PAINT ORANGE (-4110 1935);
DISPLAY INVISIBLE (-4110 1935);
FORCEPROP 2 LAST CDS_LIB mstr_standard
J 2
(-4300 1900);
PAINT ORANGE (-4300 1900);
DISPLAY INVISIBLE (-4300 1900);
FORCEPROP 1 LAST COMMENT_BODY TRUE
J 0
(-4345 1805);
DISPLAY 0.893617 (-4345 1805);
PAINT GREEN (-4345 1805);
DISPLAY INVISIBLE (-4345 1805);
FORCEPROP 2 LAST ROOM PVCCIN_CPU1_VSENSE_VR
J 0
(-4700 1975);
PAINT ORANGE (-4700 1975);
DISPLAY INVISIBLE (-4700 1975);
FORCEADD RES..1
(-5500 2300);
FORCEPROP 1 LAST TOLERANCE 1%
J 0
(-5450 2225);
DISPLAY 0.617021 (-5450 2225);
PAINT SKYBLUE (-5450 2225);
FORCEPROP 1 LASTPIN (-5400 2300) $PN 2
J 0
(-5438 2312);
DISPLAY 0.617021 (-5438 2312);
PAINT GREEN (-5438 2312);
FORCEPROP 1 LAST PART_NUMBER G21796-017
J 0
(-5550 2400);
DISPLAY 0.617021 (-5550 2400);
PAINT BLUE (-5550 2400);
FORCEPROP 1 LAST LOCATION R1E4
J 0
(-5550 2350);
DISPLAY 0.617021 (-5550 2350);
PAINT AQUA (-5550 2350);
FORCEPROP 1 LAST VALUE 100.0
J 2
(-5500 2225);
DISPLAY 0.617021 (-5500 2225);
PAINT SKYBLUE (-5500 2225);
FORCEPROP 1 LAST WATTAGE 1/16W
J 2
(-5500 2175);
DISPLAY 0.617021 (-5500 2175);
PAINT SKYBLUE (-5500 2175);
FORCEPROP 1 LASTPIN (-5600 2300) $PN 1
J 0
(-5588 2312);
DISPLAY 0.617021 (-5588 2312);
PAINT GREEN (-5588 2312);
FORCEPROP 1 LAST PACK_TYPE 0402
J 0
(-5575 2125);
DISPLAY 0.617021 (-5575 2125);
PAINT SKYBLUE (-5575 2125);
FORCEPROP 2 LAST ROOM PVCCIN_CPU1_VSENSE_VR
J 0
(-5550 2400);
PAINT ORANGE (-5550 2400);
DISPLAY INVISIBLE (-5550 2400);
FORCEPROP 2 LAST $SEC 1
J 0
(-5550 2500);
PAINT MONO (-5550 2500);
DISPLAY INVISIBLE (-5550 2500);
FORCEPROP 2 LAST CDS_LOCATION R1E4
J 0
(-5550 2350);
DISPLAY 0.617021 (-5550 2350);
PAINT AQUA (-5550 2350);
DISPLAY INVISIBLE (-5550 2350);
FORCEPROP 1 LAST PATH I15
J 0
(-5550 2450);
DISPLAY 0.978723 (-5550 2450);
PAINT WHITE (-5550 2450);
DISPLAY INVISIBLE (-5550 2450);
FORCEPROP 2 LAST CDS_SEC 1
J 0
(-5550 2500);
PAINT MONO (-5550 2500);
DISPLAY INVISIBLE (-5550 2500);
FORCEPROP 2 LAST BOM_COST PROC_VRD_VCCIN_CPU0
J 0
(-5550 2450);
PAINT MONO (-5550 2450);
DISPLAY INVISIBLE (-5550 2450);
FORCEPROP 2 LAST CDS_LIB mstr_discrete
J 0
(-5500 2300);
PAINT ORANGE (-5500 2300);
DISPLAY INVISIBLE (-5500 2300);
FORCEPROP 1 LAST MATERIAL CHIP
J 0
(-5475 2175);
PAINT SKYBLUE (-5475 2175);
DISPLAY INVISIBLE (-5475 2175);
FORCEADD CAP..1
(-6350 4025);
FORCEPROP 1 LAST LOCATION C1C26
J 0
(-6300 4125);
DISPLAY 0.617021 (-6300 4125);
PAINT AQUA (-6300 4125);
FORCEPROP 1 LASTPIN (-6350 4125) $PN 1
J 0
(-6340 4105);
DISPLAY 0.617021 (-6340 4105);
PAINT ORANGE (-6340 4105);
FORCEPROP 1 LAST VALUE 1.0UF
J 0
(-6300 4075);
DISPLAY 0.617021 (-6300 4075);
PAINT SKYBLUE (-6300 4075);
FORCEPROP 1 LAST PART_NUMBER D97712-011
J 0
(-6300 3875);
DISPLAY 0.617021 (-6300 3875);
PAINT BLUE (-6300 3875);
FORCEPROP 1 LAST TOLERANCE 10%
J 0
(-6300 3975);
DISPLAY 0.617021 (-6300 3975);
PAINT SKYBLUE (-6300 3975);
FORCEPROP 1 LAST VOLTAGE 16V
J 0
(-6300 4025);
DISPLAY 0.617021 (-6300 4025);
PAINT SKYBLUE (-6300 4025);
FORCEPROP 1 LAST MATERIAL X6S
J 0
(-6300 3925);
DISPLAY 0.617021 (-6300 3925);
PAINT SKYBLUE (-6300 3925);
FORCEPROP 1 LASTPIN (-6350 3925) $PN 2
J 0
(-6340 3905);
DISPLAY 0.617021 (-6340 3905);
PAINT ORANGE (-6340 3905);
FORCEPROP 1 LAST PACK_TYPE 0402
J 0
(-6300 3825);
DISPLAY 0.617021 (-6300 3825);
PAINT SKYBLUE (-6300 3825);
FORCEPROP 2 LAST SEC_TYPE 0402
J 0
(-6300 4225);
DISPLAY 1.021277 (-6300 4225);
PAINT ORANGE (-6300 4225);
DISPLAY INVISIBLE (-6300 4225);
FORCEPROP 2 LAST SEC 1
J 0
(-6300 4225);
DISPLAY 0.680851 (-6300 4225);
PAINT MONO (-6300 4225);
DISPLAY INVISIBLE (-6300 4225);
FORCEPROP 1 LAST PATH I16
J 0
(-6300 4175);
DISPLAY 0.978723 (-6300 4175);
PAINT WHITE (-6300 4175);
DISPLAY INVISIBLE (-6300 4175);
FORCEPROP 2 LAST ROOM PVCCIN_CPU1_PWR_VR
J 0
(-6300 4175);
DISPLAY 1.361702 (-6300 4175);
PAINT ORANGE (-6300 4175);
DISPLAY INVISIBLE (-6300 4175);
FORCEPROP 2 LAST CDS_LIB mstr_discrete
J 0
(-6350 4025);
PAINT ORANGE (-6350 4025);
DISPLAY INVISIBLE (-6350 4025);
FORCEADD CAP_A..1
(-6000 4050);
FORCEPROP 1 LAST LOCATION C1C25
J 0
(-5950 4150);
DISPLAY 0.617021 (-5950 4150);
PAINT AQUA (-5950 4150);
FORCEPROP 1 LASTPIN (-6000 4150) $PN 1
J 0
(-5990 4130);
DISPLAY 0.617021 (-5990 4130);
PAINT ORANGE (-5990 4130);
FORCEPROP 1 LAST TOLERANCE 10%
J 0
(-5950 4000);
DISPLAY 0.617021 (-5950 4000);
PAINT SKYBLUE (-5950 4000);
FORCEPROP 1 LAST PACK_TYPE 0402V
J 0
(-5950 3850);
DISPLAY 0.617021 (-5950 3850);
PAINT SKYBLUE (-5950 3850);
FORCEPROP 1 LAST MATERIAL X7R
J 0
(-5950 3950);
DISPLAY 0.617021 (-5950 3950);
PAINT SKYBLUE (-5950 3950);
FORCEPROP 1 LASTPIN (-6000 3950) $PN 2
J 0
(-5990 3930);
DISPLAY 0.617021 (-5990 3930);
PAINT ORANGE (-5990 3930);
FORCEPROP 1 LAST PART_NUMBER A36096-030
J 0
(-5950 3900);
DISPLAY 0.617021 (-5950 3900);
PAINT BLUE (-5950 3900);
FORCEPROP 1 LAST VOLTAGE 16V
J 0
(-5950 4050);
DISPLAY 0.617021 (-5950 4050);
PAINT SKYBLUE (-5950 4050);
FORCEPROP 1 LAST VALUE 0.1UF
J 0
(-5950 4100);
DISPLAY 0.617021 (-5950 4100);
PAINT SKYBLUE (-5950 4100);
FORCEPROP 1 LAST PATH I17
J 0
(-5950 4200);
DISPLAY 0.978723 (-5950 4200);
PAINT WHITE (-5950 4200);
DISPLAY INVISIBLE (-5950 4200);
FORCEPROP 2 LAST ROOM PVCCIN_CPU1_PWR_VR
J 0
(-5950 4200);
DISPLAY 1.361702 (-5950 4200);
PAINT ORANGE (-5950 4200);
DISPLAY INVISIBLE (-5950 4200);
FORCEPROP 2 LAST CDS_SEC 1
J 0
(-5950 4200);
PAINT ORANGE (-5950 4200);
DISPLAY INVISIBLE (-5950 4200);
FORCEPROP 2 LAST SEC_TYPE 0402V
J 0
(-5950 4250);
DISPLAY 1.021277 (-5950 4250);
PAINT ORANGE (-5950 4250);
DISPLAY INVISIBLE (-5950 4250);
FORCEPROP 2 LAST SEC 1
J 0
(-5950 4250);
DISPLAY 0.680851 (-5950 4250);
PAINT MONO (-5950 4250);
DISPLAY INVISIBLE (-5950 4250);
FORCEPROP 2 LAST CDS_LIB dev_discrete
J 0
(-6000 4050);
PAINT ORANGE (-6000 4050);
DISPLAY INVISIBLE (-6000 4050);
FORCEADD CAP..1
(-5625 4025);
FORCEPROP 1 LAST LOCATION C1D32
J 0
(-5575 4125);
DISPLAY 0.617021 (-5575 4125);
PAINT AQUA (-5575 4125);
FORCEPROP 1 LASTPIN (-5625 4125) $PN 1
J 0
(-5615 4105);
DISPLAY 0.617021 (-5615 4105);
PAINT ORANGE (-5615 4105);
FORCEPROP 1 LAST VALUE 1.0UF
J 0
(-5575 4075);
DISPLAY 0.617021 (-5575 4075);
PAINT SKYBLUE (-5575 4075);
FORCEPROP 1 LAST TOLERANCE 10%
J 0
(-5575 3975);
DISPLAY 0.617021 (-5575 3975);
PAINT SKYBLUE (-5575 3975);
FORCEPROP 1 LAST PACK_TYPE 0402
J 0
(-5575 3825);
DISPLAY 0.617021 (-5575 3825);
PAINT SKYBLUE (-5575 3825);
FORCEPROP 1 LAST VOLTAGE 16V
J 0
(-5575 4025);
DISPLAY 0.617021 (-5575 4025);
PAINT SKYBLUE (-5575 4025);
FORCEPROP 1 LASTPIN (-5625 3925) $PN 2
J 0
(-5615 3905);
DISPLAY 0.617021 (-5615 3905);
PAINT ORANGE (-5615 3905);
FORCEPROP 1 LAST PART_NUMBER D97712-011
J 0
(-5575 3875);
DISPLAY 0.617021 (-5575 3875);
PAINT BLUE (-5575 3875);
FORCEPROP 1 LAST MATERIAL X6S
J 0
(-5575 3925);
DISPLAY 0.617021 (-5575 3925);
PAINT SKYBLUE (-5575 3925);
FORCEPROP 2 LAST SEC_TYPE 0402
J 0
(-5575 4225);
DISPLAY 1.021277 (-5575 4225);
PAINT ORANGE (-5575 4225);
DISPLAY INVISIBLE (-5575 4225);
FORCEPROP 2 LAST SEC 1
J 0
(-5575 4225);
DISPLAY 0.680851 (-5575 4225);
PAINT MONO (-5575 4225);
DISPLAY INVISIBLE (-5575 4225);
FORCEPROP 2 LAST ROOM PVCCIN_CPU1_PWR_VR
J 0
(-5575 4175);
DISPLAY 1.361702 (-5575 4175);
PAINT ORANGE (-5575 4175);
DISPLAY INVISIBLE (-5575 4175);
FORCEPROP 1 LAST PATH I18
J 0
(-5575 4175);
DISPLAY 0.978723 (-5575 4175);
PAINT WHITE (-5575 4175);
DISPLAY INVISIBLE (-5575 4175);
FORCEPROP 2 LAST CDS_LIB mstr_discrete
J 0
(-5625 4025);
PAINT ORANGE (-5625 4025);
DISPLAY INVISIBLE (-5625 4025);
FORCEADD PVCCIN_CPU1..1
(-4650 2450);
FORCEPROP 3 LASTPIN (-4650 2400) SIG_NAME PVCCIN_CPU1\g
J 0
(-4640 2410);
DISPLAY 0.659574 (-4640 2410);
PAINT MONO (-4640 2410);
DISPLAY INVISIBLE (-4640 2410);
FORCEPROP 1 LAST VOLTAGE 2.0V
J 0
(-4695 2407);
DISPLAY 0.340426 (-4695 2407);
PAINT SKYBLUE (-4695 2407);
DISPLAY INVISIBLE (-4695 2407);
FORCEPROP 2 LAST CDS_LIB mstr_symbols
J 0
(-4650 2450);
PAINT ORANGE (-4650 2450);
DISPLAY INVISIBLE (-4650 2450);
FORCEPROP 1 LAST BODY_TYPE PLUMBING
J 0
(-4695 2407);
DISPLAY 0.340426 (-4695 2407);
PAINT GREEN (-4695 2407);
DISPLAY INVISIBLE (-4695 2407);
FORCEPROP 1 LAST PATH I19
J 0
(-4600 2475);
DISPLAY 0.872340 (-4600 2475);
PAINT AQUA (-4600 2475);
DISPLAY INVISIBLE (-4600 2475);
FORCEPROP 1 LAST HDL_POWER PVCCIN_CPU1
J 1
(-4650 2500);
DISPLAY 0.872340 (-4650 2500);
PAINT GREEN (-4650 2500);
DISPLAY INVISIBLE (-4650 2500);
FORCEADD OFFPAGE..1
(-7625 1850);
FORCEPROP 2 LAST $XR0 206 
J 0
(-7877 1850);
DISPLAY 0.638298 (-7877 1850);
PAINT MONO (-7877 1850);
FORCEPROP 1 LAST OFFPAGE TRUE
J 0
(-7300 1725);
DISPLAY 0.893617 (-7300 1725);
PAINT GREEN (-7300 1725);
DISPLAY INVISIBLE (-7300 1725);
FORCEPROP 2 LAST CDS_LIB mstr_standard
J 2
(-7625 1850);
PAINT ORANGE (-7625 1850);
DISPLAY INVISIBLE (-7625 1850);
FORCEPROP 1 LAST COMMENT_BODY TRUE
J 0
(-7500 1750);
DISPLAY 0.893617 (-7500 1750);
PAINT GREEN (-7500 1750);
DISPLAY INVISIBLE (-7500 1750);
FORCEPROP 2 LAST PATH I2
J 0
(-7860 1885);
DISPLAY 1.021277 (-7860 1885);
PAINT ORANGE (-7860 1885);
DISPLAY INVISIBLE (-7860 1885);
FORCEPROP 2 LAST BOM_COST PROC_VRD_VCCIN_CPU0
J 0
(-7825 1900);
PAINT MONO (-7825 1900);
DISPLAY INVISIBLE (-7825 1900);
FORCEPROP 2 LAST ROOM PVCCIN_CPU1_VSENSE_VR
J 0
(-8150 1925);
PAINT ORANGE (-8150 1925);
DISPLAY INVISIBLE (-8150 1925);
FORCEADD CAP..1
R 2
(-5575 3450);
FORCEPROP 1 LASTPIN (-5575 3550) $PN 1
J 2
(-5585 3530);
DISPLAY 0.617021 (-5585 3530);
PAINT ORANGE (-5585 3530);
FORCEPROP 1 LASTPIN (-5575 3350) $PN 2
J 2
(-5585 3330);
DISPLAY 0.617021 (-5585 3330);
PAINT ORANGE (-5585 3330);
FORCEPROP 1 LAST LOCATION C1C24
J 2
(-5625 3550);
DISPLAY 0.617021 (-5625 3550);
PAINT AQUA (-5625 3550);
FORCEPROP 1 LAST VALUE 0.220UF
J 2
(-5625 3500);
DISPLAY 0.617021 (-5625 3500);
PAINT SKYBLUE (-5625 3500);
FORCEPROP 1 LAST PACK_TYPE 0402
J 2
(-5625 3250);
DISPLAY 0.617021 (-5625 3250);
PAINT SKYBLUE (-5625 3250);
FORCEPROP 1 LAST PART_NUMBER A36096-104
J 2
(-5625 3300);
DISPLAY 0.617021 (-5625 3300);
PAINT BLUE (-5625 3300);
FORCEPROP 1 LAST MATERIAL X7R
J 2
(-5625 3350);
DISPLAY 0.617021 (-5625 3350);
PAINT SKYBLUE (-5625 3350);
FORCEPROP 1 LAST TOLERANCE 10%
J 2
(-5625 3400);
DISPLAY 0.617021 (-5625 3400);
PAINT SKYBLUE (-5625 3400);
FORCEPROP 1 LAST VOLTAGE 16V
J 2
(-5625 3450);
DISPLAY 0.617021 (-5625 3450);
PAINT SKYBLUE (-5625 3450);
FORCEPROP 2 LAST SEC_TYPE 0402
J 0
(-5625 3650);
DISPLAY 1.021277 (-5625 3650);
PAINT ORANGE (-5625 3650);
DISPLAY INVISIBLE (-5625 3650);
FORCEPROP 0 LAST SPOF TRUE
J 0
(-5625 3650);
DISPLAY 1.021277 (-5625 3650);
PAINT ORANGE (-5625 3650);
DISPLAY INVISIBLE (-5625 3650);
FORCEPROP 2 LAST SEC 1
J 0
(-5625 3650);
PAINT MONO (-5625 3650);
DISPLAY INVISIBLE (-5625 3650);
FORCEPROP 2 LAST NO_XNET_CONNECTION 1
J 0
(-5625 3650);
PAINT MONO (-5625 3650);
DISPLAY INVISIBLE (-5625 3650);
FORCEPROP 1 LAST PATH I20
J 2
(-5625 3600);
DISPLAY 0.978723 (-5625 3600);
PAINT WHITE (-5625 3600);
DISPLAY INVISIBLE (-5625 3600);
FORCEPROP 2 LAST ROOM PVCCIN_CPU1_PWR_VR
J 0
(-5650 3600);
DISPLAY 1.361702 (-5650 3600);
PAINT ORANGE (-5650 3600);
DISPLAY INVISIBLE (-5650 3600);
FORCEPROP 2 LAST CDS_LIB mstr_discrete
J 0
(-5575 3450);
PAINT ORANGE (-5575 3450);
DISPLAY INVISIBLE (-5575 3450);
FORCEPROP 2 LAST CDS_LOCATION C1C24
J 2
(-5625 3550);
DISPLAY 0.617021 (-5625 3550);
PAINT AQUA (-5625 3550);
DISPLAY INVISIBLE (-5625 3550);
FORCEADD CAP_A..1
R 2
(-4975 4050);
FORCEPROP 1 LAST VALUE 1.0UF
J 2
(-5025 4100);
DISPLAY 0.617021 (-5025 4100);
PAINT SKYBLUE (-5025 4100);
FORCEPROP 1 LAST TOLERANCE 10%
J 2
(-5025 4000);
DISPLAY 0.617021 (-5025 4000);
PAINT SKYBLUE (-5025 4000);
FORCEPROP 1 LASTPIN (-4975 4150) $PN 1
J 2
(-4985 4130);
DISPLAY 0.617021 (-4985 4130);
PAINT ORANGE (-4985 4130);
FORCEPROP 1 LAST LOCATION C1C18
J 2
(-5025 4150);
DISPLAY 0.617021 (-5025 4150);
PAINT AQUA (-5025 4150);
FORCEPROP 1 LAST MATERIAL X6S
J 2
(-5025 3950);
DISPLAY 0.617021 (-5025 3950);
PAINT SKYBLUE (-5025 3950);
FORCEPROP 1 LASTPIN (-4975 3950) $PN 2
J 2
(-4985 3930);
DISPLAY 0.617021 (-4985 3930);
PAINT ORANGE (-4985 3930);
FORCEPROP 1 LAST PART_NUMBER D97712-004
J 2
(-5025 3900);
DISPLAY 0.617021 (-5025 3900);
PAINT BLUE (-5025 3900);
FORCEPROP 1 LAST VOLTAGE 6.3V
J 2
(-5025 4050);
DISPLAY 0.617021 (-5025 4050);
PAINT SKYBLUE (-5025 4050);
FORCEPROP 1 LAST PACK_TYPE 0402V
J 2
(-5025 3850);
DISPLAY 0.617021 (-5025 3850);
PAINT SKYBLUE (-5025 3850);
FORCEPROP 2 LAST ROOM PVCCIN_CPU1_PWR_VR
J 0
(-5025 4200);
DISPLAY 1.361702 (-5025 4200);
PAINT ORANGE (-5025 4200);
DISPLAY INVISIBLE (-5025 4200);
FORCEPROP 2 LAST SEC 1
J 0
(-5025 4250);
DISPLAY 0.680851 (-5025 4250);
PAINT MONO (-5025 4250);
DISPLAY INVISIBLE (-5025 4250);
FORCEPROP 1 LAST PATH I21
J 2
(-5025 4200);
DISPLAY 0.978723 (-5025 4200);
PAINT WHITE (-5025 4200);
DISPLAY INVISIBLE (-5025 4200);
FORCEPROP 2 LAST CDS_LOCATION C1C18
J 2
(-5025 4150);
DISPLAY 0.617021 (-5025 4150);
PAINT AQUA (-5025 4150);
DISPLAY INVISIBLE (-5025 4150);
FORCEPROP 2 LAST SEC_TYPE 0402V
J 0
(-5025 4250);
DISPLAY 1.021277 (-5025 4250);
PAINT ORANGE (-5025 4250);
DISPLAY INVISIBLE (-5025 4250);
FORCEPROP 2 LAST CDS_SEC 1
J 0
(-5025 4200);
PAINT ORANGE (-5025 4200);
DISPLAY INVISIBLE (-5025 4200);
FORCEPROP 2 LAST CDS_LIB dev_discrete
J 0
(-4975 4050);
PAINT ORANGE (-4975 4050);
DISPLAY INVISIBLE (-4975 4050);
FORCEADD CAP..1
(-4875 4050);
FORCEPROP 1 LAST PACK_TYPE 0402
J 0
(-4825 3850);
DISPLAY 0.617021 (-4825 3850);
PAINT SKYBLUE (-4825 3850);
FORCEPROP 1 LAST PART_NUMBER A36096-155
J 0
(-4825 3900);
DISPLAY 0.617021 (-4825 3900);
PAINT BLUE (-4825 3900);
FORCEPROP 1 LASTPIN (-4875 3950) $PN 2
J 0
(-4865 3930);
DISPLAY 0.617021 (-4865 3930);
PAINT ORANGE (-4865 3930);
FORCEPROP 1 LAST LOCATION C1D33
J 0
(-4825 4150);
DISPLAY 0.617021 (-4825 4150);
PAINT AQUA (-4825 4150);
FORCEPROP 1 LAST VALUE 0.22UF
J 0
(-4825 4100);
DISPLAY 0.617021 (-4825 4100);
PAINT SKYBLUE (-4825 4100);
FORCEPROP 1 LASTPIN (-4875 4150) $PN 1
J 0
(-4865 4130);
DISPLAY 0.617021 (-4865 4130);
PAINT ORANGE (-4865 4130);
FORCEPROP 1 LAST TOLERANCE 10%
J 0
(-4825 4000);
DISPLAY 0.617021 (-4825 4000);
PAINT SKYBLUE (-4825 4000);
FORCEPROP 1 LAST VOLTAGE 16V
J 0
(-4825 4050);
DISPLAY 0.617021 (-4825 4050);
PAINT SKYBLUE (-4825 4050);
FORCEPROP 1 LAST MATERIAL X7R
J 0
(-4825 3950);
DISPLAY 0.617021 (-4825 3950);
PAINT SKYBLUE (-4825 3950);
FORCEPROP 2 LAST SEC_TYPE 0402
J 0
(-4825 4250);
DISPLAY 1.021277 (-4825 4250);
PAINT ORANGE (-4825 4250);
DISPLAY INVISIBLE (-4825 4250);
FORCEPROP 2 LAST SEC 1
J 0
(-4825 4250);
DISPLAY 0.680851 (-4825 4250);
PAINT MONO (-4825 4250);
DISPLAY INVISIBLE (-4825 4250);
FORCEPROP 1 LAST PATH I22
J 0
(-4825 4200);
DISPLAY 0.978723 (-4825 4200);
PAINT WHITE (-4825 4200);
DISPLAY INVISIBLE (-4825 4200);
FORCEPROP 2 LAST ROOM PVCCIN_CPU1_PWR_VR
J 0
(-4825 4200);
DISPLAY 1.361702 (-4825 4200);
PAINT ORANGE (-4825 4200);
DISPLAY INVISIBLE (-4825 4200);
FORCEPROP 2 LAST CDS_LIB mstr_discrete
J 0
(-4875 4050);
PAINT ORANGE (-4875 4050);
DISPLAY INVISIBLE (-4875 4050);
FORCEADD VCC_CORE..1
(-7175 4525);
FORCEPROP 3 LASTPIN (-7175 4475) SIG_NAME VR_FET_SW_P12V_STBY_PVCCIN_CPU1\g
J 0
(-7165 4485);
DISPLAY 0.659574 (-7165 4485);
PAINT MONO (-7165 4485);
DISPLAY INVISIBLE (-7165 4485);
FORCEPROP 1 LAST HDL_POWER VR_FET_SW_P12V_STBY_PVCCIN_CPU1
J 1
(-7125 4575);
DISPLAY 0.617021 (-7125 4575);
PAINT GREEN (-7125 4575);
FORCEPROP 1 LAST PATH I23
J 0
(-7125 4550);
DISPLAY 0.872340 (-7125 4550);
PAINT AQUA (-7125 4550);
DISPLAY INVISIBLE (-7125 4550);
FORCEPROP 2 LAST CDS_LIB mstr_symbols
J 0
(-7175 4525);
DISPLAY 1.936170 (-7175 4525);
PAINT ORANGE (-7175 4525);
DISPLAY INVISIBLE (-7175 4525);
FORCEADD RES..1
(-5300 4650);
FORCEPROP 1 LAST MATERIAL CHIP
J 0
(-5225 4475);
DISPLAY 0.617021 (-5225 4475);
PAINT SKYBLUE (-5225 4475);
FORCEPROP 1 LASTPIN (-5200 4650) $PN 2
J 0
(-5238 4662);
DISPLAY 0.617021 (-5238 4662);
PAINT ORANGE (-5238 4662);
FORCEPROP 1 LAST LOCATION R9P32
J 0
(-5350 4700);
DISPLAY 0.617021 (-5350 4700);
PAINT AQUA (-5350 4700);
FORCEPROP 1 LASTPIN (-5400 4650) $PN 1
J 0
(-5388 4662);
DISPLAY 0.617021 (-5388 4662);
PAINT ORANGE (-5388 4662);
FORCEPROP 1 LAST PACK_TYPE 0402
J 0
(-5250 4525);
DISPLAY 0.617021 (-5250 4525);
PAINT SKYBLUE (-5250 4525);
FORCEPROP 1 LAST TOLERANCE 1%
J 0
(-5350 4525);
DISPLAY 0.617021 (-5350 4525);
PAINT SKYBLUE (-5350 4525);
FORCEPROP 1 LAST WATTAGE 1/16W
J 2
(-5275 4475);
DISPLAY 0.617021 (-5275 4475);
PAINT SKYBLUE (-5275 4475);
FORCEPROP 1 LAST PART_NUMBER G21796-090
J 0
(-5425 4575);
DISPLAY 0.617021 (-5425 4575);
PAINT BLUE (-5425 4575);
FORCEPROP 1 LAST VALUE 1.0
J 2
(-5400 4525);
DISPLAY 0.617021 (-5400 4525);
PAINT SKYBLUE (-5400 4525);
FORCEPROP 2 LAST SEC_TYPE 0402
J 0
(-5350 4850);
DISPLAY 1.021277 (-5350 4850);
PAINT ORANGE (-5350 4850);
DISPLAY INVISIBLE (-5350 4850);
FORCEPROP 2 LAST SEC 1
J 0
(-5350 4850);
DISPLAY 0.680851 (-5350 4850);
PAINT MONO (-5350 4850);
DISPLAY INVISIBLE (-5350 4850);
FORCEPROP 2 LAST ROOM PVCCIN_CPU1_PWR_VR
J 0
(-5350 4750);
DISPLAY 1.361702 (-5350 4750);
PAINT ORANGE (-5350 4750);
DISPLAY INVISIBLE (-5350 4750);
FORCEPROP 1 LAST PATH I24
J 0
(-5350 4800);
DISPLAY 0.978723 (-5350 4800);
PAINT WHITE (-5350 4800);
DISPLAY INVISIBLE (-5350 4800);
FORCEPROP 2 LAST CDS_LIB mstr_discrete
J 0
(-5300 4650);
PAINT ORANGE (-5300 4650);
DISPLAY INVISIBLE (-5300 4650);
FORCEADD GND..1
(-3300 1000);
FORCEPROP 3 LASTPIN (-3300 1050) SIG_NAME GND\g
J 0
(-3290 1060);
DISPLAY 0.659574 (-3290 1060);
PAINT MONO (-3290 1060);
DISPLAY INVISIBLE (-3290 1060);
FORCEPROP 1 LAST HDL_POWER GND
J 0
(-3300 1150);
DISPLAY 0.893617 (-3300 1150);
PAINT GREEN (-3300 1150);
DISPLAY INVISIBLE (-3300 1150);
FORCEPROP 2 LAST BOM_COST PROC_VRD_VCCIN_CPU0
J 0
(-3675 1075);
PAINT MONO (-3675 1075);
DISPLAY INVISIBLE (-3675 1075);
FORCEPROP 2 LAST ROOM PVCCIN_CPU1_FILTER_VR
J 0
(-3850 1075);
PAINT ORANGE (-3850 1075);
DISPLAY INVISIBLE (-3850 1075);
FORCEPROP 1 LAST VOLTAGE 0
J 0
(-3300 1000);
PAINT SKYBLUE (-3300 1000);
DISPLAY INVISIBLE (-3300 1000);
FORCEPROP 2 LAST CDS_LIB mstr_symbols
J 0
(-3300 1000);
PAINT ORANGE (-3300 1000);
DISPLAY INVISIBLE (-3300 1000);
FORCEPROP 1 LAST PATH I26
J 0
(-3225 1000);
DISPLAY 0.872340 (-3225 1000);
PAINT AQUA (-3225 1000);
DISPLAY INVISIBLE (-3225 1000);
FORCEPROP 1 LAST SIZE 1B
J 0
(-3225 950);
DISPLAY 0.893617 (-3225 950);
PAINT GREEN (-3225 950);
DISPLAY INVISIBLE (-3225 950);
FORCEPROP 1 LAST BODY_TYPE PLUMBING
J 0
(-3345 957);
DISPLAY 0.340426 (-3345 957);
PAINT GREEN (-3345 957);
DISPLAY INVISIBLE (-3345 957);
FORCEADD OFFPAGE..2
R 2
(-3850 1675);
FORCEPROP 2 LAST $XR0 206 
J 0
(-4105 1675);
DISPLAY 0.638298 (-4105 1675);
PAINT MONO (-4105 1675);
FORCEPROP 2 LAST ROOM PVCCIN_CPU1_FILTER_VR
J 2
(-3450 1750);
PAINT ORANGE (-3450 1750);
DISPLAY INVISIBLE (-3450 1750);
FORCEPROP 1 LAST COMMENT_BODY TRUE
J 2
(-3805 1580);
DISPLAY 0.893617 (-3805 1580);
PAINT GREEN (-3805 1580);
DISPLAY INVISIBLE (-3805 1580);
FORCEPROP 2 LAST CDS_LIB mstr_standard
J 2
(-3850 1675);
PAINT ORANGE (-3850 1675);
DISPLAY INVISIBLE (-3850 1675);
FORCEPROP 2 LAST BOM_COST PROC_VRD_VCCIN_CPU0
J 2
(-4050 1725);
PAINT MONO (-4050 1725);
DISPLAY INVISIBLE (-4050 1725);
FORCEPROP 1 LAST OFFPAGE TRUE
J 2
(-4175 1550);
DISPLAY 0.893617 (-4175 1550);
PAINT GREEN (-4175 1550);
DISPLAY INVISIBLE (-4175 1550);
FORCEPROP 2 LAST PATH I27
J 0
(-4135 1710);
DISPLAY 1.021277 (-4135 1710);
PAINT ORANGE (-4135 1710);
DISPLAY INVISIBLE (-4135 1710);
FORCEADD GND..1
(-2250 850);
FORCEPROP 3 LASTPIN (-2250 900) SIG_NAME GND\g
J 0
(-2240 910);
DISPLAY 0.659574 (-2240 910);
PAINT MONO (-2240 910);
DISPLAY INVISIBLE (-2240 910);
FORCEPROP 1 LAST HDL_POWER GND
J 0
(-2250 1000);
DISPLAY 0.893617 (-2250 1000);
PAINT GREEN (-2250 1000);
DISPLAY INVISIBLE (-2250 1000);
FORCEPROP 1 LAST PATH I29
J 0
(-2175 850);
DISPLAY 0.872340 (-2175 850);
PAINT AQUA (-2175 850);
DISPLAY INVISIBLE (-2175 850);
FORCEPROP 1 LAST BODY_TYPE PLUMBING
J 0
(-2295 807);
DISPLAY 0.340426 (-2295 807);
PAINT GREEN (-2295 807);
DISPLAY INVISIBLE (-2295 807);
FORCEPROP 2 LAST CDS_LIB mstr_symbols
J 0
(-2250 850);
PAINT ORANGE (-2250 850);
DISPLAY INVISIBLE (-2250 850);
FORCEPROP 1 LAST SIZE 1B
J 0
(-2175 800);
DISPLAY 0.893617 (-2175 800);
PAINT GREEN (-2175 800);
DISPLAY INVISIBLE (-2175 800);
FORCEPROP 1 LAST VOLTAGE 0
J 0
(-2250 850);
PAINT SKYBLUE (-2250 850);
DISPLAY INVISIBLE (-2250 850);
FORCEPROP 2 LAST BOM_COST PROC_VRD_VCCIN_CPU0
J 0
(-2625 925);
PAINT MONO (-2625 925);
DISPLAY INVISIBLE (-2625 925);
FORCEPROP 2 LAST ROOM PVCCIN_CPU1_FILTER_VR
J 0
(-2800 925);
PAINT ORANGE (-2800 925);
DISPLAY INVISIBLE (-2800 925);
FORCEADD RES..2
(-6300 1700);
FORCEPROP 1 LAST MATERIAL EMPTY
J 0
(-6260 1625);
DISPLAY 0.617021 (-6260 1625);
PAINT RED (-6260 1625);
FORCEPROP 1 LAST LOCATION R1E5
J 0
(-6255 1825);
DISPLAY 0.617021 (-6255 1825);
PAINT AQUA (-6255 1825);
FORCEPROP 1 LAST PART_NUMBER G21796-026
J 0
(-6260 1575);
DISPLAY 0.617021 (-6260 1575);
PAINT BLUE (-6260 1575);
FORCEPROP 1 LAST VALUE 1.00K
J 0
(-6255 1775);
DISPLAY 0.617021 (-6255 1775);
PAINT SKYBLUE (-6255 1775);
FORCEPROP 1 LAST PACK_TYPE 0402
J 0
(-6260 1525);
DISPLAY 0.617021 (-6260 1525);
PAINT SKYBLUE (-6260 1525);
FORCEPROP 1 LAST WATTAGE 1/16W
J 0
(-6260 1675);
DISPLAY 0.617021 (-6260 1675);
PAINT SKYBLUE (-6260 1675);
FORCEPROP 1 LAST TOLERANCE 1%
J 0
(-6255 1725);
DISPLAY 0.617021 (-6255 1725);
PAINT SKYBLUE (-6255 1725);
FORCEPROP 1 LASTPIN (-6300 1600) $PN 2
J 0
(-6295 1610);
DISPLAY 0.617021 (-6295 1610);
PAINT GREEN (-6295 1610);
FORCEPROP 1 LASTPIN (-6300 1800) $PN 1
J 0
(-6295 1762);
DISPLAY 0.617021 (-6295 1762);
PAINT GREEN (-6295 1762);
FORCEPROP 2 LAST BOM_COST PROC_VRD_VCCIN_CPU0
J 0
(-6250 1875);
PAINT MONO (-6250 1875);
DISPLAY INVISIBLE (-6250 1875);
FORCEPROP 2 LAST CDS_SEC 1
J 0
(-6250 1925);
PAINT MONO (-6250 1925);
DISPLAY INVISIBLE (-6250 1925);
FORCEPROP 2 LAST $SEC 1
J 0
(-6250 1925);
PAINT MONO (-6250 1925);
DISPLAY INVISIBLE (-6250 1925);
FORCEPROP 2 LAST CDS_LOCATION R1E5
J 0
(-6255 1825);
DISPLAY 0.617021 (-6255 1825);
PAINT AQUA (-6255 1825);
DISPLAY INVISIBLE (-6255 1825);
FORCEPROP 1 LAST PATH I3
J 0
(-6250 1875);
DISPLAY 0.978723 (-6250 1875);
PAINT WHITE (-6250 1875);
DISPLAY INVISIBLE (-6250 1875);
FORCEPROP 2 LAST ROOM PVCCIN_CPU1_VSENSE_VR
J 0
(-6250 1875);
PAINT MONO (-6250 1875);
DISPLAY INVISIBLE (-6250 1875);
FORCEPROP 2 LAST CDS_LIB mstr_discrete
J 0
(-6300 1700);
PAINT ORANGE (-6300 1700);
DISPLAY INVISIBLE (-6300 1700);
FORCEADD CAP_A..1
(-2250 1125);
FORCEPROP 1 LAST MATERIAL EMPTY
J 0
(-2200 1025);
DISPLAY 0.617021 (-2200 1025);
PAINT RED (-2200 1025);
FORCEPROP 1 LAST PART_NUMBER A36096-030
J 0
(-2200 975);
DISPLAY 0.617021 (-2200 975);
PAINT BLUE (-2200 975);
FORCEPROP 1 LAST LOCATION C1B16
J 0
(-2200 1225);
DISPLAY 0.617021 (-2200 1225);
PAINT AQUA (-2200 1225);
FORCEPROP 1 LAST VALUE 0.1UF
J 0
(-2200 1175);
DISPLAY 0.617021 (-2200 1175);
PAINT SKYBLUE (-2200 1175);
FORCEPROP 1 LAST TOLERANCE 10%
J 0
(-2200 1075);
DISPLAY 0.617021 (-2200 1075);
PAINT SKYBLUE (-2200 1075);
FORCEPROP 1 LAST VOLTAGE 16V
J 0
(-2200 1125);
DISPLAY 0.617021 (-2200 1125);
PAINT SKYBLUE (-2200 1125);
FORCEPROP 1 LAST PACK_TYPE 0402V
J 0
(-2200 925);
DISPLAY 0.617021 (-2200 925);
PAINT SKYBLUE (-2200 925);
FORCEPROP 2 LAST CDS_SEC 1
J 0
(-2200 1325);
PAINT MONO (-2200 1325);
DISPLAY INVISIBLE (-2200 1325);
FORCEPROP 2 LAST ROOM PVCCIN_CPU1_FILTER_VR
J 0
(-2200 1275);
DISPLAY 1.361702 (-2200 1275);
PAINT ORANGE (-2200 1275);
DISPLAY INVISIBLE (-2200 1275);
FORCEPROP 1 LAST PATH I30
J 0
(-2200 1275);
DISPLAY 0.978723 (-2200 1275);
PAINT WHITE (-2200 1275);
DISPLAY INVISIBLE (-2200 1275);
FORCEPROP 2 LAST CDS_LOCATION C1B16
J 0
(-2200 1225);
DISPLAY 0.617021 (-2200 1225);
PAINT AQUA (-2200 1225);
DISPLAY INVISIBLE (-2200 1225);
FORCEPROP 1 LASTPIN (-2250 1225) $PN 1
J 0
(-2240 1205);
DISPLAY 0.787234 (-2240 1205);
PAINT ORANGE (-2240 1205);
DISPLAY INVISIBLE (-2240 1205);
FORCEPROP 2 LAST CDS_LIB dev_discrete
J 0
(-2250 1125);
PAINT ORANGE (-2250 1125);
DISPLAY INVISIBLE (-2250 1125);
FORCEPROP 1 LASTPIN (-2250 1025) $PN 2
J 0
(-2240 1005);
DISPLAY 0.787234 (-2240 1005);
PAINT ORANGE (-2240 1005);
DISPLAY INVISIBLE (-2240 1005);
FORCEADD INDUCTOR..1
(-3000 2250);
FORCEPROP 1 LAST PART_NUMBER D92183-019
J 0
(-3150 2175);
DISPLAY 0.617021 (-3150 2175);
PAINT BLUE (-3150 2175);
FORCEPROP 1 LAST PACK_TYPE SM
J 0
(-2810 2115);
DISPLAY 0.617021 (-2810 2115);
PAINT SKYBLUE (-2810 2115);
FORCEPROP 1 LAST VALUE 100NH
J 2
(-3005 2115);
DISPLAY 0.617021 (-3005 2115);
PAINT SKYBLUE (-3005 2115);
FORCEPROP 1 LASTPIN (-2900 2250) $PN 2
J 2
(-2890 2260);
DISPLAY 0.617021 (-2890 2260);
PAINT WHITE (-2890 2260);
FORCEPROP 1 LAST LOCATION L1B2
J 0
(-3100 2300);
DISPLAY 0.617021 (-3100 2300);
PAINT AQUA (-3100 2300);
FORCEPROP 1 LASTPIN (-3100 2250) $PN 1
J 0
(-3100 2260);
DISPLAY 0.617021 (-3100 2260);
PAINT WHITE (-3100 2260);
FORCEPROP 1 LAST MATERIAL IND
J 0
(-2960 2115);
DISPLAY 0.617021 (-2960 2115);
PAINT SKYBLUE (-2960 2115);
FORCEPROP 2 LAST CDS_LIB mstr_discrete
J 0
(-3000 2250);
PAINT ORANGE (-3000 2250);
DISPLAY INVISIBLE (-3000 2250);
FORCEPROP 2 LAST SEC 1
J 0
(-3100 2450);
DISPLAY 0.680851 (-3100 2450);
PAINT MONO (-3100 2450);
DISPLAY INVISIBLE (-3100 2450);
FORCEPROP 2 LAST SEC_TYPE SM
J 0
(-3100 2450);
DISPLAY 1.021277 (-3100 2450);
PAINT ORANGE (-3100 2450);
DISPLAY INVISIBLE (-3100 2450);
FORCEPROP 2 LAST CDS_LOCATION L1B2
J 0
(-3100 2300);
DISPLAY 0.617021 (-3100 2300);
PAINT AQUA (-3100 2300);
DISPLAY INVISIBLE (-3100 2300);
FORCEPROP 1 LAST PATH I32
J 0
(-3100 2400);
DISPLAY 0.978723 (-3100 2400);
PAINT ORANGE (-3100 2400);
DISPLAY INVISIBLE (-3100 2400);
FORCEPROP 2 LAST ROOM PVCCIN_CPU1_FILTER_VR
J 0
(-3100 2350);
DISPLAY 1.361702 (-3100 2350);
PAINT ORANGE (-3100 2350);
DISPLAY INVISIBLE (-3100 2350);
FORCEADD GND..1
(-2675 3125);
FORCEPROP 3 LASTPIN (-2675 3175) SIG_NAME GND\g
J 0
(-2665 3185);
DISPLAY 0.659574 (-2665 3185);
PAINT MONO (-2665 3185);
DISPLAY INVISIBLE (-2665 3185);
FORCEPROP 1 LAST HDL_POWER GND
J 0
(-2675 3275);
DISPLAY 1.723404 (-2675 3275);
PAINT GREEN (-2675 3275);
DISPLAY INVISIBLE (-2675 3275);
FORCEPROP 2 LAST CDS_LIB mstr_symbols
J 0
(-2675 3125);
DISPLAY 1.936170 (-2675 3125);
PAINT ORANGE (-2675 3125);
DISPLAY INVISIBLE (-2675 3125);
FORCEPROP 1 LAST PATH I34
J 0
(-2600 3125);
DISPLAY 0.872340 (-2600 3125);
PAINT AQUA (-2600 3125);
DISPLAY INVISIBLE (-2600 3125);
FORCEPROP 1 LAST SIZE 1B
J 0
(-2600 3075);
DISPLAY 1.723404 (-2600 3075);
PAINT GREEN (-2600 3075);
DISPLAY INVISIBLE (-2600 3075);
FORCEPROP 1 LAST VOLTAGE 0
J 0
(-2675 3125);
PAINT SKYBLUE (-2675 3125);
DISPLAY INVISIBLE (-2675 3125);
FORCEPROP 1 LAST BODY_TYPE PLUMBING
J 0
(-2720 3082);
DISPLAY 0.340426 (-2720 3082);
PAINT GREEN (-2720 3082);
DISPLAY INVISIBLE (-2720 3082);
FORCEPROP 2 LAST BOM_COST PROC_VRD_VCCIN_CPU0
J 0
(-3050 3200);
DISPLAY 1.446809 (-3050 3200);
PAINT MONO (-3050 3200);
DISPLAY INVISIBLE (-3050 3200);
FORCEPROP 2 LAST ROOM PVCCIN_CPU1_PWR_VR
J 0
(-3225 3200);
DISPLAY 1.936170 (-3225 3200);
PAINT ORANGE (-3225 3200);
DISPLAY INVISIBLE (-3225 3200);
FORCEADD CAPP..1
(-1425 2075);
FORCEPROP 1 LAST VALUE 270UF
J 0
(-1375 2125);
DISPLAY 0.617021 (-1375 2125);
PAINT SKYBLUE (-1375 2125);
FORCEPROP 1 LAST TOLERANCE 20%
J 0
(-1375 2075);
DISPLAY 0.617021 (-1375 2075);
PAINT SKYBLUE (-1375 2075);
FORCEPROP 1 LASTPIN (-1425 1975) $PN 2
J 0
(-1415 1960);
DISPLAY 0.617021 (-1415 1960);
PAINT ORANGE (-1415 1960);
FORCEPROP 1 LAST LOCATION C1C1
J 0
(-1375 2175);
DISPLAY 0.617021 (-1375 2175);
PAINT AQUA (-1375 2175);
FORCEPROP 1 LASTPIN (-1425 2175) $PN 1
J 0
(-1415 2160);
DISPLAY 0.617021 (-1415 2160);
PAINT ORANGE (-1415 2160);
FORCEPROP 1 LAST PACK_TYPE 2626
J 0
(-1375 1925);
DISPLAY 0.617021 (-1375 1925);
PAINT SKYBLUE (-1375 1925);
FORCEPROP 1 LAST MATERIAL OSCON
J 0
(-1375 1975);
DISPLAY 0.617021 (-1375 1975);
PAINT SKYBLUE (-1375 1975);
FORCEPROP 1 LAST VOLTAGE 16V
J 0
(-1375 2025);
DISPLAY 0.617021 (-1375 2025);
PAINT SKYBLUE (-1375 2025);
FORCEPROP 1 LAST PART_NUMBER A31228-047
J 0
(-1375 1875);
DISPLAY 0.617021 (-1375 1875);
PAINT BLUE (-1375 1875);
FORCEPROP 2 LAST SEC_TYPE 2626
J 0
(-1375 2275);
DISPLAY 1.021277 (-1375 2275);
PAINT ORANGE (-1375 2275);
DISPLAY INVISIBLE (-1375 2275);
FORCEPROP 2 LAST SEC 1
J 0
(-1375 2275);
DISPLAY 0.680851 (-1375 2275);
PAINT MONO (-1375 2275);
DISPLAY INVISIBLE (-1375 2275);
FORCEPROP 2 LAST CDS_LOCATION C1C1
J 0
(-1375 2175);
DISPLAY 0.617021 (-1375 2175);
PAINT AQUA (-1375 2175);
DISPLAY INVISIBLE (-1375 2175);
FORCEPROP 1 LAST PATH I35
J 0
(-1375 2225);
DISPLAY 0.978723 (-1375 2225);
PAINT ORANGE (-1375 2225);
DISPLAY INVISIBLE (-1375 2225);
FORCEPROP 2 LAST ROOM PVCCIN_CPU1_FILTER_VR
J 0
(-1375 2225);
DISPLAY 1.361702 (-1375 2225);
PAINT ORANGE (-1375 2225);
DISPLAY INVISIBLE (-1375 2225);
FORCEPROP 2 LAST CDS_LIB mstr_discrete
J 0
(-1425 2075);
PAINT ORANGE (-1425 2075);
DISPLAY INVISIBLE (-1425 2075);
FORCEADD GND..1
(-1200 1650);
FORCEPROP 3 LASTPIN (-1200 1700) SIG_NAME GND\g
J 0
(-1190 1710);
DISPLAY 0.659574 (-1190 1710);
PAINT MONO (-1190 1710);
DISPLAY INVISIBLE (-1190 1710);
FORCEPROP 1 LAST HDL_POWER GND
J 0
(-1200 1800);
DISPLAY 0.893617 (-1200 1800);
PAINT GREEN (-1200 1800);
DISPLAY INVISIBLE (-1200 1800);
FORCEPROP 1 LAST PATH I36
J 0
(-1125 1650);
DISPLAY 0.872340 (-1125 1650);
PAINT AQUA (-1125 1650);
DISPLAY INVISIBLE (-1125 1650);
FORCEPROP 1 LAST SIZE 1B
J 0
(-1125 1600);
DISPLAY 0.893617 (-1125 1600);
PAINT GREEN (-1125 1600);
DISPLAY INVISIBLE (-1125 1600);
FORCEPROP 1 LAST VOLTAGE 0
J 0
(-1200 1650);
PAINT SKYBLUE (-1200 1650);
DISPLAY INVISIBLE (-1200 1650);
FORCEPROP 2 LAST CDS_LIB mstr_symbols
J 0
(-1200 1650);
PAINT ORANGE (-1200 1650);
DISPLAY INVISIBLE (-1200 1650);
FORCEPROP 1 LAST BODY_TYPE PLUMBING
J 0
(-1245 1607);
DISPLAY 0.340426 (-1245 1607);
PAINT GREEN (-1245 1607);
DISPLAY INVISIBLE (-1245 1607);
FORCEPROP 2 LAST ROOM PVCCIN_CPU1_FILTER_VR
J 0
(-1750 1725);
PAINT ORANGE (-1750 1725);
DISPLAY INVISIBLE (-1750 1725);
FORCEPROP 2 LAST BOM_COST PROC_VRD_VCCIN_CPU0
J 0
(-1575 1725);
PAINT MONO (-1575 1725);
DISPLAY INVISIBLE (-1575 1725);
FORCEADD CAPP..1
(-950 2050);
FORCEPROP 1 LAST VOLTAGE 16V
J 0
(-900 2000);
DISPLAY 0.617021 (-900 2000);
PAINT SKYBLUE (-900 2000);
FORCEPROP 1 LAST TOLERANCE 20%
J 0
(-900 2050);
DISPLAY 0.617021 (-900 2050);
PAINT SKYBLUE (-900 2050);
FORCEPROP 1 LAST VALUE 270UF
J 0
(-900 2100);
DISPLAY 0.617021 (-900 2100);
PAINT SKYBLUE (-900 2100);
FORCEPROP 1 LASTPIN (-950 2150) $PN 1
J 0
(-940 2135);
DISPLAY 0.617021 (-940 2135);
PAINT ORANGE (-940 2135);
FORCEPROP 1 LAST PART_NUMBER A31228-047
J 0
(-900 1850);
DISPLAY 0.617021 (-900 1850);
PAINT BLUE (-900 1850);
FORCEPROP 1 LAST MATERIAL OSCON
J 0
(-900 1950);
DISPLAY 0.617021 (-900 1950);
PAINT SKYBLUE (-900 1950);
FORCEPROP 1 LAST PACK_TYPE 2626
J 0
(-900 1900);
DISPLAY 0.617021 (-900 1900);
PAINT SKYBLUE (-900 1900);
FORCEPROP 1 LASTPIN (-950 1950) $PN 2
J 0
(-940 1935);
DISPLAY 0.617021 (-940 1935);
PAINT ORANGE (-940 1935);
FORCEPROP 1 LAST LOCATION C1E18
J 0
(-900 2150);
DISPLAY 0.617021 (-900 2150);
PAINT AQUA (-900 2150);
FORCEPROP 2 LAST ROOM PVCCIN_CPU1_FILTER_VR
J 0
(-900 2200);
DISPLAY 1.361702 (-900 2200);
PAINT ORANGE (-900 2200);
DISPLAY INVISIBLE (-900 2200);
FORCEPROP 1 LAST PATH I37
J 0
(-900 2200);
DISPLAY 0.978723 (-900 2200);
PAINT ORANGE (-900 2200);
DISPLAY INVISIBLE (-900 2200);
FORCEPROP 2 LAST SEC 1
J 0
(-900 2250);
DISPLAY 0.680851 (-900 2250);
PAINT MONO (-900 2250);
DISPLAY INVISIBLE (-900 2250);
FORCEPROP 2 LAST SEC_TYPE 2626
J 0
(-900 2250);
DISPLAY 1.021277 (-900 2250);
PAINT ORANGE (-900 2250);
DISPLAY INVISIBLE (-900 2250);
FORCEPROP 2 LAST CDS_LOCATION C1E18
J 0
(-900 2150);
DISPLAY 0.617021 (-900 2150);
PAINT AQUA (-900 2150);
DISPLAY INVISIBLE (-900 2150);
FORCEPROP 2 LAST CDS_LIB mstr_discrete
J 0
(-950 2050);
PAINT ORANGE (-950 2050);
DISPLAY INVISIBLE (-950 2050);
FORCEADD CAPP..1
(-600 2050);
FORCEPROP 1 LAST LOCATION C1C2
J 0
(-550 2150);
DISPLAY 0.617021 (-550 2150);
PAINT AQUA (-550 2150);
FORCEPROP 1 LAST VALUE 270UF
J 0
(-550 2100);
DISPLAY 0.617021 (-550 2100);
PAINT SKYBLUE (-550 2100);
FORCEPROP 1 LASTPIN (-600 2150) $PN 1
J 0
(-590 2135);
DISPLAY 0.617021 (-590 2135);
PAINT ORANGE (-590 2135);
FORCEPROP 1 LAST PART_NUMBER A31228-047
J 0
(-550 1850);
DISPLAY 0.617021 (-550 1850);
PAINT BLUE (-550 1850);
FORCEPROP 1 LAST TOLERANCE 20%
J 0
(-550 2050);
DISPLAY 0.617021 (-550 2050);
PAINT SKYBLUE (-550 2050);
FORCEPROP 1 LAST VOLTAGE 16V
J 0
(-550 2000);
DISPLAY 0.617021 (-550 2000);
PAINT SKYBLUE (-550 2000);
FORCEPROP 1 LAST MATERIAL OSCON
J 0
(-550 1950);
DISPLAY 0.617021 (-550 1950);
PAINT SKYBLUE (-550 1950);
FORCEPROP 1 LASTPIN (-600 1950) $PN 2
J 0
(-590 1935);
DISPLAY 0.617021 (-590 1935);
PAINT ORANGE (-590 1935);
FORCEPROP 1 LAST PACK_TYPE 2626
J 0
(-550 1900);
DISPLAY 0.617021 (-550 1900);
PAINT SKYBLUE (-550 1900);
FORCEPROP 2 LAST SEC 1
J 0
(-550 2250);
DISPLAY 0.680851 (-550 2250);
PAINT MONO (-550 2250);
DISPLAY INVISIBLE (-550 2250);
FORCEPROP 2 LAST SEC_TYPE 2626
J 0
(-550 2250);
DISPLAY 1.021277 (-550 2250);
PAINT ORANGE (-550 2250);
DISPLAY INVISIBLE (-550 2250);
FORCEPROP 1 LAST PATH I38
J 0
(-550 2200);
DISPLAY 0.978723 (-550 2200);
PAINT ORANGE (-550 2200);
DISPLAY INVISIBLE (-550 2200);
FORCEPROP 2 LAST ROOM PVCCIN_CPU1_FILTER_VR
J 0
(-550 2200);
DISPLAY 1.361702 (-550 2200);
PAINT ORANGE (-550 2200);
DISPLAY INVISIBLE (-550 2200);
FORCEPROP 2 LAST CDS_LIB mstr_discrete
J 0
(-600 2050);
PAINT ORANGE (-600 2050);
DISPLAY INVISIBLE (-600 2050);
FORCEPROP 2 LAST CDS_LOCATION C1C2
J 0
(-550 2150);
DISPLAY 0.617021 (-550 2150);
PAINT AQUA (-550 2150);
DISPLAY INVISIBLE (-550 2150);
FORCEADD RES..1
(-1850 2250);
FORCEPROP 1 LAST PACK_TYPE 2010
J 0
(-1600 2100);
DISPLAY 0.617021 (-1600 2100);
PAINT SKYBLUE (-1600 2100);
FORCEPROP 1 LAST TOLERANCE 1%
J 0
(-1850 2150);
DISPLAY 0.617021 (-1850 2150);
PAINT SKYBLUE (-1850 2150);
FORCEPROP 1 LAST MATERIAL CHIP
J 0
(-1850 2100);
DISPLAY 0.617021 (-1850 2100);
PAINT SKYBLUE (-1850 2100);
FORCEPROP 1 LAST VALUE 0.001
J 2
(-1875 2150);
DISPLAY 0.617021 (-1875 2150);
PAINT SKYBLUE (-1875 2150);
FORCEPROP 1 LAST WATTAGE 1W
J 2
(-1875 2100);
DISPLAY 0.617021 (-1875 2100);
PAINT SKYBLUE (-1875 2100);
FORCEPROP 1 LASTPIN (-1950 2250) $PN 1
J 0
(-1938 2262);
DISPLAY 0.617021 (-1938 2262);
PAINT ORANGE (-1938 2262);
FORCEPROP 1 LASTPIN (-1750 2250) $PN 2
J 0
(-1788 2262);
DISPLAY 0.617021 (-1788 2262);
PAINT ORANGE (-1788 2262);
FORCEPROP 1 LAST LOCATION R1B20
J 0
(-1900 2300);
DISPLAY 0.617021 (-1900 2300);
PAINT AQUA (-1900 2300);
FORCEPROP 1 LAST PART_NUMBER E30969-002
J 0
(-1900 2350);
DISPLAY 0.617021 (-1900 2350);
PAINT BLUE (-1900 2350);
FORCEPROP 2 LAST ROOM PVCCIN_CPU1_FILTER_VR
J 0
(-1900 2350);
DISPLAY 1.361702 (-1900 2350);
PAINT ORANGE (-1900 2350);
DISPLAY INVISIBLE (-1900 2350);
FORCEPROP 1 LAST PATH I39
J 0
(-1900 2400);
DISPLAY 0.978723 (-1900 2400);
PAINT WHITE (-1900 2400);
DISPLAY INVISIBLE (-1900 2400);
FORCEPROP 2 LAST SEC 1
J 0
(-1900 2450);
DISPLAY 0.680851 (-1900 2450);
PAINT MONO (-1900 2450);
DISPLAY INVISIBLE (-1900 2450);
FORCEPROP 2 LAST SEC_TYPE 2010
J 0
(-1900 2450);
DISPLAY 1.021277 (-1900 2450);
PAINT ORANGE (-1900 2450);
DISPLAY INVISIBLE (-1900 2450);
FORCEPROP 2 LAST CDS_LOCATION R1B20
J 0
(-1900 2300);
DISPLAY 0.617021 (-1900 2300);
PAINT AQUA (-1900 2300);
DISPLAY INVISIBLE (-1900 2300);
FORCEPROP 2 LAST CDS_LIB mstr_discrete
J 0
(-1850 2250);
PAINT ORANGE (-1850 2250);
DISPLAY INVISIBLE (-1850 2250);
FORCEADD GND..1
(-7175 3500);
FORCEPROP 3 LASTPIN (-7175 3550) SIG_NAME GND\g
J 0
(-7165 3560);
DISPLAY 0.659574 (-7165 3560);
PAINT MONO (-7165 3560);
DISPLAY INVISIBLE (-7165 3560);
FORCEPROP 1 LAST SIZE 1B
J 0
(-7100 3450);
DISPLAY 1.723404 (-7100 3450);
PAINT GREEN (-7100 3450);
DISPLAY INVISIBLE (-7100 3450);
FORCEPROP 1 LAST PATH I4
J 0
(-7100 3500);
DISPLAY 0.872340 (-7100 3500);
PAINT AQUA (-7100 3500);
DISPLAY INVISIBLE (-7100 3500);
FORCEPROP 1 LAST HDL_POWER GND
J 0
(-7175 3650);
DISPLAY 1.723404 (-7175 3650);
PAINT GREEN (-7175 3650);
DISPLAY INVISIBLE (-7175 3650);
FORCEPROP 2 LAST BOM_COST PROC_VRD_VCCIN_CPU0
J 0
(-7550 3575);
DISPLAY 1.446809 (-7550 3575);
PAINT MONO (-7550 3575);
DISPLAY INVISIBLE (-7550 3575);
FORCEPROP 1 LAST VOLTAGE 0
J 0
(-7175 3500);
PAINT SKYBLUE (-7175 3500);
DISPLAY INVISIBLE (-7175 3500);
FORCEPROP 2 LAST CDS_LIB mstr_symbols
J 0
(-7175 3500);
DISPLAY 1.936170 (-7175 3500);
PAINT ORANGE (-7175 3500);
DISPLAY INVISIBLE (-7175 3500);
FORCEPROP 1 LAST BODY_TYPE PLUMBING
J 0
(-7220 3457);
DISPLAY 0.340426 (-7220 3457);
PAINT GREEN (-7220 3457);
DISPLAY INVISIBLE (-7220 3457);
FORCEPROP 2 LAST ROOM PVCCIN_CPU1_PWR_VR
J 0
(-7725 3575);
DISPLAY 1.936170 (-7725 3575);
PAINT ORANGE (-7725 3575);
DISPLAY INVISIBLE (-7725 3575);
FORCEADD INDUCTOR..1
(-1450 3475);
FORCEPROP 1 LAST VALUE 0.12UH
J 2
(-1455 3365);
DISPLAY 0.617021 (-1455 3365);
PAINT SKYBLUE (-1455 3365);
FORCEPROP 1 LAST PART_NUMBER D92183-034
J 0
(-1575 3425);
DISPLAY 0.617021 (-1575 3425);
PAINT BLUE (-1575 3425);
FORCEPROP 1 LASTPIN (-1350 3475) $PN 2
J 2
(-1340 3485);
DISPLAY 0.617021 (-1340 3485);
PAINT WHITE (-1340 3485);
FORCEPROP 1 LASTPIN (-1550 3475) $PN 1
J 0
(-1550 3485);
DISPLAY 0.617021 (-1550 3485);
PAINT WHITE (-1550 3485);
FORCEPROP 1 LAST LOCATION L1C2
J 0
(-1550 3525);
DISPLAY 0.617021 (-1550 3525);
PAINT AQUA (-1550 3525);
FORCEPROP 1 LAST PACK_TYPE SM
J 0
(-1285 3365);
DISPLAY 0.617021 (-1285 3365);
PAINT SKYBLUE (-1285 3365);
FORCEPROP 1 LAST MATERIAL IND
J 0
(-1410 3365);
DISPLAY 0.617021 (-1410 3365);
PAINT SKYBLUE (-1410 3365);
FORCEPROP 2 LAST CDS_LIB mstr_discrete
J 0
(-1450 3475);
PAINT ORANGE (-1450 3475);
DISPLAY INVISIBLE (-1450 3475);
FORCEPROP 1 LAST PATH I40
J 0
(-1550 3625);
DISPLAY 0.978723 (-1550 3625);
PAINT ORANGE (-1550 3625);
DISPLAY INVISIBLE (-1550 3625);
FORCEPROP 2 LAST $SEC 1
J 0
(-1550 3675);
PAINT MONO (-1550 3675);
DISPLAY INVISIBLE (-1550 3675);
FORCEPROP 2 LAST CDS_SEC 1
J 0
(-1550 3675);
PAINT MONO (-1550 3675);
DISPLAY INVISIBLE (-1550 3675);
FORCEPROP 2 LAST ROOM PVCCIN_CPU1_PWR_VR
J 0
(-1550 3575);
DISPLAY 1.361702 (-1550 3575);
PAINT ORANGE (-1550 3575);
DISPLAY INVISIBLE (-1550 3575);
FORCEPROP 2 LAST CDS_LOCATION L1C2
J 0
(-1550 3525);
DISPLAY 0.617021 (-1550 3525);
PAINT AQUA (-1550 3525);
DISPLAY INVISIBLE (-1550 3525);
FORCEADD GND..1
(-375 2850);
FORCEPROP 3 LASTPIN (-375 2900) SIG_NAME GND\g
J 0
(-365 2910);
DISPLAY 0.659574 (-365 2910);
PAINT MONO (-365 2910);
DISPLAY INVISIBLE (-365 2910);
FORCEPROP 1 LAST HDL_POWER GND
J 0
(-375 3000);
DISPLAY 1.723404 (-375 3000);
PAINT GREEN (-375 3000);
DISPLAY INVISIBLE (-375 3000);
FORCEPROP 1 LAST VOLTAGE 0
J 0
(-375 2850);
PAINT SKYBLUE (-375 2850);
DISPLAY INVISIBLE (-375 2850);
FORCEPROP 2 LAST CDS_LIB mstr_symbols
J 0
(-375 2850);
DISPLAY 1.936170 (-375 2850);
PAINT ORANGE (-375 2850);
DISPLAY INVISIBLE (-375 2850);
FORCEPROP 1 LAST PATH I41
J 0
(-300 2850);
DISPLAY 0.872340 (-300 2850);
PAINT AQUA (-300 2850);
DISPLAY INVISIBLE (-300 2850);
FORCEPROP 1 LAST SIZE 1B
J 0
(-300 2800);
DISPLAY 1.723404 (-300 2800);
PAINT GREEN (-300 2800);
DISPLAY INVISIBLE (-300 2800);
FORCEPROP 1 LAST BODY_TYPE PLUMBING
J 0
(-420 2807);
DISPLAY 0.340426 (-420 2807);
PAINT GREEN (-420 2807);
DISPLAY INVISIBLE (-420 2807);
FORCEPROP 2 LAST BOM_COST PROC_VRD_VCCIN_CPU0
J 0
(-750 2925);
DISPLAY 1.446809 (-750 2925);
PAINT MONO (-750 2925);
DISPLAY INVISIBLE (-750 2925);
FORCEPROP 2 LAST ROOM PVCCIN_CPU1_PWR_VR
J 0
(-925 2925);
DISPLAY 1.936170 (-925 2925);
PAINT ORANGE (-925 2925);
DISPLAY INVISIBLE (-925 2925);
FORCEADD CAP_A..1
(-750 3225);
FORCEPROP 1 LAST PART_NUMBER E15431-004
J 0
(-700 3075);
DISPLAY 0.617021 (-700 3075);
PAINT BLUE (-700 3075);
FORCEPROP 1 LASTPIN (-750 3325) $PN 1
J 0
(-740 3305);
DISPLAY 0.617021 (-740 3305);
PAINT GREEN (-740 3305);
FORCEPROP 1 LAST LOCATION C1D24
J 0
(-700 3325);
DISPLAY 0.617021 (-700 3325);
PAINT AQUA (-700 3325);
FORCEPROP 1 LAST VALUE 22.0UF
J 0
(-700 3275);
DISPLAY 0.617021 (-700 3275);
PAINT SKYBLUE (-700 3275);
FORCEPROP 1 LAST TOLERANCE 20%
J 0
(-700 3175);
DISPLAY 0.617021 (-700 3175);
PAINT SKYBLUE (-700 3175);
FORCEPROP 1 LAST VOLTAGE 4V
J 0
(-700 3225);
DISPLAY 0.617021 (-700 3225);
PAINT SKYBLUE (-700 3225);
FORCEPROP 1 LAST MATERIAL X6S
J 0
(-700 3125);
DISPLAY 0.617021 (-700 3125);
PAINT SKYBLUE (-700 3125);
FORCEPROP 1 LASTPIN (-750 3125) $PN 2
J 0
(-740 3105);
DISPLAY 0.617021 (-740 3105);
PAINT GREEN (-740 3105);
FORCEPROP 1 LAST PACK_TYPE 0603V
J 0
(-700 3025);
DISPLAY 0.617021 (-700 3025);
PAINT SKYBLUE (-700 3025);
FORCEPROP 2 LAST BOM_COST PROC_VRD_VCCIN_CPU0
J 0
(-700 3375);
DISPLAY 1.446809 (-700 3375);
PAINT MONO (-700 3375);
DISPLAY INVISIBLE (-700 3375);
FORCEPROP 2 LAST CDS_SEC 1
J 0
(-700 3375);
PAINT ORANGE (-700 3375);
DISPLAY INVISIBLE (-700 3375);
FORCEPROP 2 LAST SEC_TYPE 0603V
J 0
(-695 3425);
DISPLAY 1.021277 (-695 3425);
PAINT ORANGE (-695 3425);
DISPLAY INVISIBLE (-695 3425);
FORCEPROP 2 LAST SEC 1
J 0
(-695 3425);
DISPLAY 0.680851 (-695 3425);
PAINT MONO (-695 3425);
DISPLAY INVISIBLE (-695 3425);
FORCEPROP 1 LAST PATH I42
J 0
(-700 3375);
DISPLAY 0.978723 (-700 3375);
PAINT WHITE (-700 3375);
DISPLAY INVISIBLE (-700 3375);
FORCEPROP 2 LAST ROOM PVCCIN_CPU1_PWR_VR
J 0
(-700 3375);
DISPLAY 1.446809 (-700 3375);
PAINT MONO (-700 3375);
DISPLAY INVISIBLE (-700 3375);
FORCEPROP 2 LAST CDS_LOCATION C1D24
J 0
(-700 3325);
DISPLAY 0.617021 (-700 3325);
PAINT AQUA (-700 3325);
DISPLAY INVISIBLE (-700 3325);
FORCEPROP 2 LAST CDS_LIB dev_discrete
J 0
(-750 3225);
PAINT ORANGE (-750 3225);
DISPLAY INVISIBLE (-750 3225);
FORCEADD PVCCIN_CPU1..1
(-225 3650);
FORCEPROP 3 LASTPIN (-225 3600) SIG_NAME PVCCIN_CPU1\g
J 0
(-215 3610);
DISPLAY 0.659574 (-215 3610);
PAINT MONO (-215 3610);
DISPLAY INVISIBLE (-215 3610);
FORCEPROP 1 LAST HDL_POWER PVCCIN_CPU1
J 1
(-225 3700);
DISPLAY 0.872340 (-225 3700);
PAINT GREEN (-225 3700);
DISPLAY INVISIBLE (-225 3700);
FORCEPROP 1 LAST PATH I43
J 0
(-175 3675);
DISPLAY 0.872340 (-175 3675);
PAINT AQUA (-175 3675);
DISPLAY INVISIBLE (-175 3675);
FORCEPROP 1 LAST BODY_TYPE PLUMBING
J 0
(-270 3607);
DISPLAY 0.340426 (-270 3607);
PAINT GREEN (-270 3607);
DISPLAY INVISIBLE (-270 3607);
FORCEPROP 2 LAST CDS_LIB mstr_symbols
J 0
(-225 3650);
PAINT ORANGE (-225 3650);
DISPLAY INVISIBLE (-225 3650);
FORCEPROP 1 LAST VOLTAGE 2.0V
J 0
(-270 3607);
DISPLAY 0.340426 (-270 3607);
PAINT SKYBLUE (-270 3607);
DISPLAY INVISIBLE (-270 3607);
FORCEADD OFFPAGE..2
(-1700 3975);
FORCEPROP 2 LAST $XR2 206 
J 0
(-1271 3975);
DISPLAY 0.638298 (-1271 3975);
PAINT MONO (-1271 3975);
FORCEPROP 2 LAST $XR1 208 
J 0
(-1391 3975);
DISPLAY 0.638298 (-1391 3975);
PAINT MONO (-1391 3975);
FORCEPROP 2 LAST $XR0 207 
J 0
(-1511 3975);
DISPLAY 0.638298 (-1511 3975);
PAINT MONO (-1511 3975);
FORCEPROP 2 LAST PATH I44
J 0
(-1270 4025);
DISPLAY 1.021277 (-1270 4025);
PAINT ORANGE (-1270 4025);
DISPLAY INVISIBLE (-1270 4025);
FORCEPROP 2 LAST BOM_COST PROC_VRD_VCCIN_CPU0
J 0
(-1500 4025);
DISPLAY 1.446809 (-1500 4025);
PAINT MONO (-1500 4025);
DISPLAY INVISIBLE (-1500 4025);
FORCEPROP 1 LAST OFFPAGE TRUE
J 0
(-1375 3850);
DISPLAY 1.723404 (-1375 3850);
PAINT GREEN (-1375 3850);
DISPLAY INVISIBLE (-1375 3850);
FORCEPROP 2 LAST CDS_LIB mstr_standard
J 0
(-1700 3975);
PAINT ORANGE (-1700 3975);
DISPLAY INVISIBLE (-1700 3975);
FORCEPROP 1 LAST COMMENT_BODY TRUE
J 0
(-1745 3880);
DISPLAY 1.723404 (-1745 3880);
PAINT GREEN (-1745 3880);
DISPLAY INVISIBLE (-1745 3880);
FORCEPROP 2 LAST ROOM PVCCIN_CPU1_PWR_VR
J 0
(-2100 4050);
DISPLAY 1.936170 (-2100 4050);
PAINT ORANGE (-2100 4050);
DISPLAY INVISIBLE (-2100 4050);
FORCEADD VCC_CORE..1
(-600 2525);
FORCEPROP 3 LASTPIN (-600 2475) SIG_NAME VR_FET_SW_P12V_STBY_PVCCIN_CPU1\g
J 0
(-590 2485);
DISPLAY 0.659574 (-590 2485);
PAINT MONO (-590 2485);
DISPLAY INVISIBLE (-590 2485);
FORCEPROP 1 LAST HDL_POWER VR_FET_SW_P12V_STBY_PVCCIN_CPU1
J 1
(-600 2575);
DISPLAY 0.617021 (-600 2575);
PAINT GREEN (-600 2575);
FORCEPROP 2 LAST CDS_LIB mstr_symbols
J 0
(-600 2525);
PAINT ORANGE (-600 2525);
DISPLAY INVISIBLE (-600 2525);
FORCEPROP 1 LAST PATH I45
J 0
(-550 2550);
DISPLAY 0.872340 (-550 2550);
PAINT AQUA (-550 2550);
DISPLAY INVISIBLE (-550 2550);
FORCEADD OFFPAGE..2
(-1150 4325);
FORCEPROP 2 LAST $XR0 206 
J 0
(-961 4325);
DISPLAY 0.638298 (-961 4325);
PAINT MONO (-961 4325);
FORCEPROP 2 LAST BOM_COST PROC_VRD_VCCIN_CPU0
J 0
(-950 4375);
DISPLAY 1.446809 (-950 4375);
PAINT MONO (-950 4375);
DISPLAY INVISIBLE (-950 4375);
FORCEPROP 1 LAST OFFPAGE TRUE
J 0
(-825 4200);
DISPLAY 1.723404 (-825 4200);
PAINT GREEN (-825 4200);
DISPLAY INVISIBLE (-825 4200);
FORCEPROP 2 LAST PATH I49
J 0
(-945 4375);
DISPLAY 1.021277 (-945 4375);
PAINT ORANGE (-945 4375);
DISPLAY INVISIBLE (-945 4375);
FORCEPROP 2 LAST CDS_LIB mstr_standard
J 0
(-1150 4325);
DISPLAY 1.936170 (-1150 4325);
PAINT ORANGE (-1150 4325);
DISPLAY INVISIBLE (-1150 4325);
FORCEPROP 1 LAST COMMENT_BODY TRUE
J 0
(-1195 4230);
DISPLAY 1.723404 (-1195 4230);
PAINT GREEN (-1195 4230);
DISPLAY INVISIBLE (-1195 4230);
FORCEPROP 2 LAST ROOM PVCCIN_CPU1_PWR_VR
J 0
(-1550 4400);
DISPLAY 1.936170 (-1550 4400);
PAINT ORANGE (-1550 4400);
DISPLAY INVISIBLE (-1550 4400);
FORCEADD CAP..1
(-7175 4025);
FORCEPROP 1 LASTPIN (-7175 4125) $PN 1
J 0
(-7165 4105);
DISPLAY 0.617021 (-7165 4105);
PAINT ORANGE (-7165 4105);
FORCEPROP 1 LAST TOLERANCE 10%
J 0
(-7125 3975);
DISPLAY 0.617021 (-7125 3975);
PAINT SKYBLUE (-7125 3975);
FORCEPROP 1 LAST VOLTAGE 16V
J 0
(-7125 4025);
DISPLAY 0.617021 (-7125 4025);
PAINT SKYBLUE (-7125 4025);
FORCEPROP 1 LAST MATERIAL X6S
J 0
(-7125 3925);
DISPLAY 0.617021 (-7125 3925);
PAINT SKYBLUE (-7125 3925);
FORCEPROP 1 LASTPIN (-7175 3925) $PN 2
J 0
(-7165 3905);
DISPLAY 0.617021 (-7165 3905);
PAINT ORANGE (-7165 3905);
FORCEPROP 1 LAST PACK_TYPE 0805
J 0
(-7125 3825);
DISPLAY 0.617021 (-7125 3825);
PAINT SKYBLUE (-7125 3825);
FORCEPROP 1 LAST PART_NUMBER C95333-007
J 0
(-7125 3875);
DISPLAY 0.617021 (-7125 3875);
PAINT BLUE (-7125 3875);
FORCEPROP 1 LAST VALUE 10UF
J 0
(-7125 4075);
DISPLAY 0.617021 (-7125 4075);
PAINT SKYBLUE (-7125 4075);
FORCEPROP 1 LAST LOCATION C9N27
J 0
(-7125 4125);
DISPLAY 0.617021 (-7125 4125);
PAINT AQUA (-7125 4125);
FORCEPROP 2 LAST SEC_TYPE 0805
J 0
(-7125 4225);
DISPLAY 1.021277 (-7125 4225);
PAINT ORANGE (-7125 4225);
DISPLAY INVISIBLE (-7125 4225);
FORCEPROP 2 LAST SEC 1
J 0
(-7125 4225);
DISPLAY 0.680851 (-7125 4225);
PAINT MONO (-7125 4225);
DISPLAY INVISIBLE (-7125 4225);
FORCEPROP 1 LAST PATH I5
J 0
(-7125 4175);
DISPLAY 0.978723 (-7125 4175);
PAINT WHITE (-7125 4175);
DISPLAY INVISIBLE (-7125 4175);
FORCEPROP 2 LAST ROOM PVCCIN_CPU1_PWR_VR
J 0
(-7125 4175);
DISPLAY 1.361702 (-7125 4175);
PAINT ORANGE (-7125 4175);
DISPLAY INVISIBLE (-7125 4175);
FORCEPROP 2 LAST CDS_LIB mstr_discrete
J 0
(-7175 4025);
PAINT ORANGE (-7175 4025);
DISPLAY INVISIBLE (-7175 4025);
FORCEADD ADM4073..1
R 2
(-2775 1350);
FORCEPROP 2 LASTPIN (-2425 1450) $PN 3
J 0
(-2415 1460);
DISPLAY 0.617021 (-2415 1460);
PAINT ORANGE (-2415 1460);
FORCEPROP 1 LAST LOCATION U1B3
J 2
(-2475 1700);
DISPLAY 0.617021 (-2475 1700);
PAINT AQUA (-2475 1700);
FORCEPROP 2 LASTPIN (-2425 1350) $PN 4
J 0
(-2415 1360);
DISPLAY 0.617021 (-2415 1360);
PAINT ORANGE (-2415 1360);
FORCEPROP 2 LASTPIN (-2425 1300) $PN 5
J 0
(-2415 1310);
DISPLAY 0.617021 (-2415 1310);
PAINT ORANGE (-2415 1310);
FORCEPROP 1 LAST PART_NUMBER G12194-001
J 2
(-2475 1050);
DISPLAY 0.617021 (-2475 1050);
PAINT BLUE (-2475 1050);
FORCEPROP 2 LASTPIN (-3125 1450) $PN 6
J 2
(-3135 1460);
DISPLAY 0.617021 (-3135 1460);
PAINT ORANGE (-3135 1460);
FORCEPROP 2 LASTPIN (-3125 1250) $PN 2
J 2
(-3135 1260);
DISPLAY 0.617021 (-3135 1260);
PAINT ORANGE (-3135 1260);
FORCEPROP 2 LASTPIN (-3125 1200) $PN 1
J 2
(-3135 1210);
DISPLAY 0.617021 (-3135 1210);
PAINT ORANGE (-3135 1210);
FORCEPROP 1 LAST MATERIAL EMPTY
J 2
(-2475 1650);
DISPLAY 0.617021 (-2475 1650);
PAINT RED (-2475 1650);
FORCEPROP 1 LAST PACK_TYPE SM
J 2
(-2475 1750);
PAINT SKYBLUE (-2475 1750);
DISPLAY INVISIBLE (-2475 1750);
FORCEPROP 2 LAST SEC_TYPE SM
J 0
(-2475 1750);
DISPLAY 1.021277 (-2475 1750);
PAINT ORANGE (-2475 1750);
DISPLAY INVISIBLE (-2475 1750);
FORCEPROP 2 LAST SEC 1
J 0
(-2475 1750);
DISPLAY 0.680851 (-2475 1750);
PAINT MONO (-2475 1750);
DISPLAY INVISIBLE (-2475 1750);
FORCEPROP 2 LAST CDS_LOCATION U1B3
J 2
(-2475 1700);
DISPLAY 0.617021 (-2475 1700);
PAINT AQUA (-2475 1700);
DISPLAY INVISIBLE (-2475 1700);
FORCEPROP 0 LAST ROOM PVCCIN_CPU1_FILTER_VR
J 0
(-2475 1800);
DISPLAY 1.021277 (-2475 1800);
PAINT ORANGE (-2475 1800);
DISPLAY INVISIBLE (-2475 1800);
FORCEPROP 1 LAST PATH I52
J 2
(-2775 1650);
PAINT GREEN (-2775 1650);
DISPLAY INVISIBLE (-2775 1650);
FORCEPROP 2 LAST CDS_LIB mstr_analog
J 2
(-2775 1350);
PAINT ORANGE (-2775 1350);
DISPLAY INVISIBLE (-2775 1350);
FORCEADD P12V_STBY..1
(-3350 2475);
FORCEPROP 3 LASTPIN (-3350 2425) SIG_NAME P12V_STBY\g
J 0
(-3340 2435);
DISPLAY 0.659574 (-3340 2435);
PAINT MONO (-3340 2435);
DISPLAY INVISIBLE (-3340 2435);
FORCEPROP 1 LAST PATH I53
J 0
(-3305 2477);
DISPLAY 0.340426 (-3305 2477);
PAINT GREEN (-3305 2477);
DISPLAY INVISIBLE (-3305 2477);
FORCEPROP 1 LAST SIZE 1B
J 0
(-3305 2497);
DISPLAY 0.340426 (-3305 2497);
PAINT GREEN (-3305 2497);
DISPLAY INVISIBLE (-3305 2497);
FORCEPROP 1 LAST BODY_TYPE PLUMBING
J 0
(-3395 2432);
DISPLAY 0.340426 (-3395 2432);
PAINT GREEN (-3395 2432);
DISPLAY INVISIBLE (-3395 2432);
FORCEPROP 2 LAST CDS_LIB mstr_symbols
J 0
(-3350 2475);
PAINT ORANGE (-3350 2475);
DISPLAY INVISIBLE (-3350 2475);
FORCEPROP 1 LAST VOLTAGE 12.0V
J 0
(-3395 2432);
DISPLAY 0.340426 (-3395 2432);
PAINT SKYBLUE (-3395 2432);
DISPLAY INVISIBLE (-3395 2432);
FORCEPROP 1 LAST HDL_POWER P12V_STBY
J 0
(-3650 2350);
DISPLAY 0.872340 (-3650 2350);
PAINT ORANGE (-3650 2350);
DISPLAY INVISIBLE (-3650 2350);
FORCEADD P5V_STBY..1
(-4550 4750);
FORCEPROP 3 LASTPIN (-4550 4700) SIG_NAME P5V_STBY\g
J 0
(-4540 4710);
DISPLAY 0.659574 (-4540 4710);
PAINT MONO (-4540 4710);
DISPLAY INVISIBLE (-4540 4710);
FORCEPROP 1 LAST PATH I54
J 0
(-4505 4752);
DISPLAY 0.340426 (-4505 4752);
PAINT GREEN (-4505 4752);
DISPLAY INVISIBLE (-4505 4752);
FORCEPROP 2 LAST CDS_LIB mstr_symbols
J 0
(-4550 4750);
PAINT ORANGE (-4550 4750);
DISPLAY INVISIBLE (-4550 4750);
FORCEPROP 1 LAST SIZE 1B
J 0
(-4505 4772);
DISPLAY 0.340426 (-4505 4772);
PAINT GREEN (-4505 4772);
DISPLAY INVISIBLE (-4505 4772);
FORCEPROP 1 LAST BODY_TYPE PLUMBING
J 0
(-4595 4707);
DISPLAY 0.340426 (-4595 4707);
PAINT GREEN (-4595 4707);
DISPLAY INVISIBLE (-4595 4707);
FORCEPROP 1 LAST VOLTAGE 5.0V
J 0
(-4595 4707);
DISPLAY 0.340426 (-4595 4707);
PAINT SKYBLUE (-4595 4707);
DISPLAY INVISIBLE (-4595 4707);
FORCEPROP 1 LAST HDL_POWER P5V_STBY
J 0
(-4850 4625);
DISPLAY 0.872340 (-4850 4625);
PAINT ORANGE (-4850 4625);
DISPLAY INVISIBLE (-4850 4625);
FORCEADD CAP_A..1
(-375 3250);
FORCEPROP 1 LAST PART_NUMBER E15431-004
J 0
(-325 3100);
DISPLAY 0.617021 (-325 3100);
PAINT BLUE (-325 3100);
FORCEPROP 1 LAST TOLERANCE 20%
J 0
(-325 3200);
DISPLAY 0.617021 (-325 3200);
PAINT SKYBLUE (-325 3200);
FORCEPROP 1 LAST MATERIAL X6S
J 0
(-325 3150);
DISPLAY 0.617021 (-325 3150);
PAINT SKYBLUE (-325 3150);
FORCEPROP 1 LASTPIN (-375 3350) $PN 1
J 0
(-365 3330);
DISPLAY 0.617021 (-365 3330);
PAINT ORANGE (-365 3330);
FORCEPROP 1 LAST VOLTAGE 4V
J 0
(-325 3250);
DISPLAY 0.617021 (-325 3250);
PAINT SKYBLUE (-325 3250);
FORCEPROP 1 LASTPIN (-375 3150) $PN 2
J 0
(-365 3130);
DISPLAY 0.617021 (-365 3130);
PAINT ORANGE (-365 3130);
FORCEPROP 1 LAST PACK_TYPE 0603V
J 0
(-325 3050);
DISPLAY 0.617021 (-325 3050);
PAINT SKYBLUE (-325 3050);
FORCEPROP 1 LAST LOCATION C9P20
J 0
(-325 3350);
DISPLAY 0.617021 (-325 3350);
PAINT AQUA (-325 3350);
FORCEPROP 1 LAST VALUE 22.0UF
J 0
(-325 3300);
DISPLAY 0.617021 (-325 3300);
PAINT SKYBLUE (-325 3300);
FORCEPROP 1 LAST PATH I55
J 0
(-325 3400);
DISPLAY 0.978723 (-325 3400);
PAINT WHITE (-325 3400);
DISPLAY INVISIBLE (-325 3400);
FORCEPROP 2 LAST CDS_SEC 1
J 0
(-325 3400);
PAINT ORANGE (-325 3400);
DISPLAY INVISIBLE (-325 3400);
FORCEPROP 2 LAST SEC_TYPE 0603V
J 0
(-325 3450);
DISPLAY 1.021277 (-325 3450);
PAINT ORANGE (-325 3450);
DISPLAY INVISIBLE (-325 3450);
FORCEPROP 2 LAST SEC 1
J 0
(-325 3450);
DISPLAY 0.680851 (-325 3450);
PAINT MONO (-325 3450);
DISPLAY INVISIBLE (-325 3450);
FORCEPROP 2 LAST CDS_LOCATION C9P20
J 0
(-325 3350);
DISPLAY 0.617021 (-325 3350);
PAINT AQUA (-325 3350);
DISPLAY INVISIBLE (-325 3350);
FORCEPROP 2 LAST CDS_LIB dev_discrete
J 0
(-375 3250);
PAINT ORANGE (-375 3250);
DISPLAY INVISIBLE (-375 3250);
FORCEADD IR354XX..1
(-3250 3775);
FORCEPROP 2 LASTPIN (-3750 3425) $PN 32
J 2
(-3760 3435);
DISPLAY 0.617021 (-3760 3435);
PAINT ORANGE (-3760 3435);
FORCEPROP 2 LASTPIN (-2750 4325) $PN 38
J 0
(-2740 4335);
DISPLAY 0.617021 (-2740 4335);
PAINT ORANGE (-2740 4335);
FORCEPROP 1 LAST VALUE IR35411
J 1
(-3250 4400);
DISPLAY 0.617021 (-3250 4400);
PAINT SKYBLUE (-3250 4400);
FORCEPROP 2 LASTPIN (-3750 3475) $PN 33
J 2
(-3760 3485);
DISPLAY 0.617021 (-3760 3485);
PAINT ORANGE (-3760 3485);
FORCEPROP 2 LASTPIN (-3750 3575) $PN 39
J 2
(-3760 3585);
DISPLAY 0.617021 (-3760 3585);
PAINT ORANGE (-3760 3585);
FORCEPROP 1 LAST LOCATION EU1C3
J 0
(-3650 4500);
DISPLAY 0.617021 (-3650 4500);
PAINT AQUA (-3650 4500);
FORCEPROP 1 LAST MATERIAL IC
J 0
(-3700 4525);
DISPLAY 0.617021 (-3700 4525);
PAINT SKYBLUE (-3700 4525);
FORCEPROP 2 LASTPIN (-3750 4325) $PN 3
J 2
(-3760 4335);
DISPLAY 0.617021 (-3760 4335);
PAINT ORANGE (-3760 4335);
FORCEPROP 2 LASTPIN (-3750 4125) $PN 4
J 2
(-3760 4135);
DISPLAY 0.617021 (-3760 4135);
PAINT ORANGE (-3760 4135);
FORCEPROP 2 LASTPIN (-3750 4275) $PN 30
J 2
(-3760 4285);
DISPLAY 0.617021 (-3760 4285);
PAINT ORANGE (-3760 4285);
FORCEPROP 2 LASTPIN (-3750 4225) $PN 25
J 2
(-3760 4235);
DISPLAY 0.617021 (-3760 4235);
PAINT ORANGE (-3760 4235);
FORCEPROP 2 LASTPIN (-2750 4075) $PN 31
J 0
(-2740 4085);
DISPLAY 0.617021 (-2740 4085);
PAINT ORANGE (-2740 4085);
FORCEPROP 2 LASTPIN (-2750 3825) $PN 36
J 0
(-2740 3835);
DISPLAY 0.617021 (-2740 3835);
PAINT ORANGE (-2740 3835);
FORCEPROP 2 LASTPIN (-2750 3475) $PN 10
J 0
(-2740 3485);
DISPLAY 0.617021 (-2740 3485);
PAINT ORANGE (-2740 3485);
FORCEPROP 2 LASTPIN (-2750 3325) $PN 40
J 0
(-2740 3335);
DISPLAY 0.617021 (-2740 3335);
PAINT ORANGE (-2740 3335);
FORCEPROP 2 LASTPIN (-2750 3275) $PN 7
J 0
(-2740 3285);
DISPLAY 0.617021 (-2740 3285);
PAINT ORANGE (-2740 3285);
FORCEPROP 2 LASTPIN (-3750 3925) $PN 1
J 2
(-3760 3935);
DISPLAY 0.617021 (-3760 3935);
PAINT ORANGE (-3760 3935);
FORCEPROP 2 LASTPIN (-3750 3775) $PN 6
J 2
(-3760 3785);
DISPLAY 0.617021 (-3760 3785);
PAINT ORANGE (-3760 3785);
FORCEPROP 2 LASTPIN (-3750 3675) $PN 34
J 2
(-3760 3685);
DISPLAY 0.617021 (-3760 3685);
PAINT ORANGE (-3760 3685);
FORCEPROP 2 LASTPIN (-3750 4025) $PN 35
J 2
(-3760 4035);
DISPLAY 0.617021 (-3760 4035);
PAINT ORANGE (-3760 4035);
FORCEPROP 2 LASTPIN (-3750 3825) $PN 41
J 2
(-3760 3835);
DISPLAY 0.617021 (-3760 3835);
PAINT ORANGE (-3760 3835);
FORCEPROP 2 LASTPIN (-2750 4125) $PN 37
J 0
(-2740 4135);
DISPLAY 0.617021 (-2740 4135);
PAINT ORANGE (-2740 4135);
FORCEPROP 2 LASTPIN (-2750 3225) $PN 5
J 0
(-2740 3235);
DISPLAY 0.617021 (-2740 3235);
PAINT ORANGE (-2740 3235);
FORCEPROP 2 LASTPIN (-2750 3375) $PN 2
J 0
(-2740 3385);
DISPLAY 0.617021 (-2740 3385);
PAINT ORANGE (-2740 3385);
FORCEPROP 1 LAST PART_NUMBER H73688-001
J 0
(-3650 3050);
DISPLAY 0.617021 (-3650 3050);
PAINT BLUE (-3650 3050);
FORCEPROP 2 LAST SEC_TYPE SM
J 0
(-3250 4575);
DISPLAY 1.021277 (-3250 4575);
PAINT ORANGE (-3250 4575);
DISPLAY INVISIBLE (-3250 4575);
FORCEPROP 2 LAST SEC 1
J 0
(-3250 4575);
DISPLAY 0.680851 (-3250 4575);
PAINT MONO (-3250 4575);
DISPLAY INVISIBLE (-3250 4575);
FORCEPROP 1 LAST PATH I56
J 0
(-3250 4525);
PAINT GREEN (-3250 4525);
DISPLAY INVISIBLE (-3250 4525);
FORCEPROP 1 LAST PACK_TYPE SM
J 0
(-3700 4625);
PAINT SKYBLUE (-3700 4625);
DISPLAY INVISIBLE (-3700 4625);
FORCEPROP 2 LAST ROOM PVCCIN_CPU1_PWR_VR
J 0
(-3650 4550);
DISPLAY 1.361702 (-3650 4550);
PAINT ORANGE (-3650 4550);
DISPLAY INVISIBLE (-3650 4550);
FORCEPROP 2 LAST CDS_LOCATION EU1C3
J 0
(-3650 4500);
DISPLAY 0.617021 (-3650 4500);
PAINT AQUA (-3650 4500);
DISPLAY INVISIBLE (-3650 4500);
FORCEPROP 2 LAST CDS_LIB mstr_discrete
J 0
(-3250 3775);
PAINT ORANGE (-3250 3775);
DISPLAY INVISIBLE (-3250 3775);
FORCEADD OFFPAGE..1
(-6225 3675);
FORCEPROP 2 LASTPIN (-6175 3675) SIG_NAME VR_PVCCIN_CPU1_PWM5
J 0
(-6160 3685);
DISPLAY 0.617021 (-6160 3685);
PAINT ORANGE (-6160 3685);
FORCEPROP 2 LAST $XR0 206 
J 0
(-6477 3675);
DISPLAY 0.638298 (-6477 3675);
PAINT MONO (-6477 3675);
FORCEPROP 1 LAST OFFPAGE TRUE
J 0
(-5900 3550);
DISPLAY 1.680851 (-5900 3550);
PAINT GREEN (-5900 3550);
DISPLAY INVISIBLE (-5900 3550);
FORCEPROP 1 LAST COMMENT_BODY TRUE
J 0
(-6100 3575);
DISPLAY 1.680851 (-6100 3575);
PAINT GREEN (-6100 3575);
DISPLAY INVISIBLE (-6100 3575);
FORCEPROP 2 LAST CDS_LIB mstr_standard
J 0
(-6225 3675);
DISPLAY 1.936170 (-6225 3675);
PAINT ORANGE (-6225 3675);
DISPLAY INVISIBLE (-6225 3675);
FORCEPROP 2 LAST PATH I57
J 0
(-6475 3725);
DISPLAY 1.021277 (-6475 3725);
PAINT ORANGE (-6475 3725);
DISPLAY INVISIBLE (-6475 3725);
FORCEPROP 2 LAST ROOM PVCCIN_CPU1_PWR_VR
J 0
(-6625 3750);
DISPLAY 1.936170 (-6625 3750);
PAINT ORANGE (-6625 3750);
DISPLAY INVISIBLE (-6625 3750);
FORCEPROP 2 LAST BOM_COST PROC_VRD_VCCIN_CPU0
J 0
(-6475 3725);
DISPLAY 1.446809 (-6475 3725);
PAINT MONO (-6475 3725);
DISPLAY INVISIBLE (-6475 3725);
FORCEADD OFFPAGE..4
(-1125 4800);
FORCEPROP 2 LAST $XR0 206 
J 0
(-939 4800);
DISPLAY 0.638298 (-939 4800);
PAINT MONO (-939 4800);
FORCEPROP 2 LAST PATH I58
J 0
(-925 4850);
DISPLAY 1.021277 (-925 4850);
PAINT ORANGE (-925 4850);
DISPLAY INVISIBLE (-925 4850);
FORCEPROP 1 LAST OFFPAGE TRUE
J 0
(-800 4675);
DISPLAY 0.872340 (-800 4675);
PAINT GREEN (-800 4675);
DISPLAY INVISIBLE (-800 4675);
FORCEPROP 2 LAST BOM_COST PROC_VRD_VCCIN_CPU0
J 0
(-925 4850);
DISPLAY 1.446809 (-925 4850);
PAINT MONO (-925 4850);
DISPLAY INVISIBLE (-925 4850);
FORCEPROP 2 LAST CDS_LIB mstr_standard
J 2
(-1125 4800);
DISPLAY 1.936170 (-1125 4800);
PAINT ORANGE (-1125 4800);
DISPLAY INVISIBLE (-1125 4800);
FORCEPROP 2 LAST ROOM PVCCIN_CPU1_PWR_VR
J 0
(-1525 4875);
DISPLAY 1.936170 (-1525 4875);
PAINT ORANGE (-1525 4875);
DISPLAY INVISIBLE (-1525 4875);
FORCEPROP 1 LAST COMMENT_BODY TRUE
J 0
(-1150 4700);
DISPLAY 0.872340 (-1150 4700);
PAINT GREEN (-1150 4700);
DISPLAY INVISIBLE (-1150 4700);
FORCEADD RES..2
(-1000 3925);
FORCEPROP 1 LAST PART_NUMBER G21796-187
J 0
(-960 3800);
DISPLAY 0.617021 (-960 3800);
PAINT BLUE (-960 3800);
FORCEPROP 1 LAST LOCATION R1D52
J 0
(-955 4050);
DISPLAY 0.617021 (-955 4050);
PAINT AQUA (-955 4050);
FORCEPROP 1 LAST MATERIAL EMPTY
J 0
(-960 3850);
DISPLAY 0.617021 (-960 3850);
PAINT RED (-960 3850);
FORCEPROP 1 LAST VALUE 68.1K
J 0
(-955 4000);
DISPLAY 0.617021 (-955 4000);
PAINT SKYBLUE (-955 4000);
FORCEPROP 1 LAST WATTAGE 1/16W
J 0
(-960 3900);
DISPLAY 0.617021 (-960 3900);
PAINT SKYBLUE (-960 3900);
FORCEPROP 1 LASTPIN (-1000 4025) $PN 1
J 0
(-995 3987);
DISPLAY 0.617021 (-995 3987);
PAINT ORANGE (-995 3987);
FORCEPROP 1 LAST TOLERANCE 1%
J 0
(-955 3950);
DISPLAY 0.617021 (-955 3950);
PAINT SKYBLUE (-955 3950);
FORCEPROP 1 LASTPIN (-1000 3825) $PN 2
J 0
(-995 3835);
DISPLAY 0.617021 (-995 3835);
PAINT ORANGE (-995 3835);
FORCEPROP 1 LAST PACK_TYPE 0402
J 0
(-960 3750);
DISPLAY 0.617021 (-960 3750);
PAINT SKYBLUE (-960 3750);
FORCEPROP 1 LAST PATH I59
J 0
(-950 4100);
DISPLAY 0.978723 (-950 4100);
PAINT WHITE (-950 4100);
DISPLAY INVISIBLE (-950 4100);
FORCEPROP 2 LAST $SEC 1
J 0
(-950 4150);
PAINT MONO (-950 4150);
DISPLAY INVISIBLE (-950 4150);
FORCEPROP 2 LAST CDS_SEC 1
J 0
(-950 4150);
PAINT MONO (-950 4150);
DISPLAY INVISIBLE (-950 4150);
FORCEPROP 2 LAST CDS_LIB mstr_discrete
J 0
(-1000 3925);
PAINT ORANGE (-1000 3925);
DISPLAY INVISIBLE (-1000 3925);
FORCEADD GND..1
(-1000 3675);
FORCEPROP 3 LASTPIN (-1000 3725) SIG_NAME GND\g
J 0
(-990 3735);
DISPLAY 0.659574 (-990 3735);
PAINT MONO (-990 3735);
DISPLAY INVISIBLE (-990 3735);
FORCEPROP 1 LAST HDL_POWER GND
J 0
(-1000 3825);
DISPLAY 0.893617 (-1000 3825);
PAINT GREEN (-1000 3825);
DISPLAY INVISIBLE (-1000 3825);
FORCEPROP 1 LAST VOLTAGE 0
J 0
(-1000 3675);
PAINT SKYBLUE (-1000 3675);
DISPLAY INVISIBLE (-1000 3675);
FORCEPROP 2 LAST CDS_LIB mstr_symbols
J 0
(-1000 3675);
PAINT ORANGE (-1000 3675);
DISPLAY INVISIBLE (-1000 3675);
FORCEPROP 1 LAST SIZE 1B
J 0
(-925 3625);
DISPLAY 0.893617 (-925 3625);
PAINT GREEN (-925 3625);
DISPLAY INVISIBLE (-925 3625);
FORCEPROP 1 LAST PATH I60
J 0
(-925 3675);
DISPLAY 0.872340 (-925 3675);
PAINT AQUA (-925 3675);
DISPLAY INVISIBLE (-925 3675);
FORCEPROP 1 LAST BODY_TYPE PLUMBING
J 0
(-1045 3632);
DISPLAY 0.340426 (-1045 3632);
PAINT GREEN (-1045 3632);
DISPLAY INVISIBLE (-1045 3632);
FORCEPROP 2 LAST BOM_COST PROC_VRD_VCCIN_CPU0
J 0
(-1375 3750);
PAINT MONO (-1375 3750);
DISPLAY INVISIBLE (-1375 3750);
FORCEPROP 2 LAST ROOM PVCCIN_CPU1_FILTER_VR
J 0
(-1550 3750);
PAINT ORANGE (-1550 3750);
DISPLAY INVISIBLE (-1550 3750);
FORCEADD CAP_A..1
(-3950 3275);
FORCEPROP 0 LAST STATUS NOPOP
J 0
(-4175 3175);
DISPLAY 1.021277 (-4175 3175);
PAINT ORANGE (-4175 3175);
FORCEPROP 1 LAST TOLERANCE 10%
J 0
(-3900 3225);
DISPLAY 0.617021 (-3900 3225);
PAINT SKYBLUE (-3900 3225);
FORCEPROP 1 LAST MATERIAL X7R
J 0
(-3900 3175);
DISPLAY 0.617021 (-3900 3175);
PAINT SKYBLUE (-3900 3175);
FORCEPROP 1 LAST LOCATION CT13
J 0
(-4100 3275);
DISPLAY 0.617021 (-4100 3275);
PAINT AQUA (-4100 3275);
FORCEPROP 1 LAST VALUE 0.1UF
J 0
(-3900 3325);
DISPLAY 0.617021 (-3900 3325);
PAINT SKYBLUE (-3900 3325);
FORCEPROP 1 LAST VOLTAGE 16V
J 0
(-3900 3275);
DISPLAY 0.617021 (-3900 3275);
PAINT SKYBLUE (-3900 3275);
FORCEPROP 1 LAST PACK_TYPE 0402V
J 0
(-3900 3075);
DISPLAY 0.617021 (-3900 3075);
PAINT SKYBLUE (-3900 3075);
FORCEPROP 1 LAST PART_NUMBER A36096-030
J 0
(-3900 3125);
DISPLAY 0.617021 (-3900 3125);
PAINT BLUE (-3900 3125);
FORCEPROP 1 LASTPIN (-3950 3175) $PN 2
J 0
(-3940 3155);
DISPLAY 0.787234 (-3940 3155);
PAINT ORANGE (-3940 3155);
DISPLAY INVISIBLE (-3940 3155);
FORCEPROP 1 LASTPIN (-3950 3375) $PN 1
J 0
(-3940 3355);
DISPLAY 0.787234 (-3940 3355);
PAINT ORANGE (-3940 3355);
DISPLAY INVISIBLE (-3940 3355);
FORCEPROP 2 LAST CDS_LIB dev_discrete
J 0
(-3950 3275);
PAINT MONO (-3950 3275);
DISPLAY INVISIBLE (-3950 3275);
FORCEPROP 1 LAST PATH I62
J 0
(-3900 3425);
DISPLAY 0.978723 (-3900 3425);
PAINT WHITE (-3900 3425);
DISPLAY INVISIBLE (-3900 3425);
FORCEPROP 2 LAST ROOM PVCCIN_CPU0_PWR_VR
J 0
(-3900 3425);
DISPLAY 1.361702 (-3900 3425);
PAINT ORANGE (-3900 3425);
DISPLAY INVISIBLE (-3900 3425);
FORCEADD GND..1
(-3950 3025);
FORCEPROP 3 LASTPIN (-3950 3075) SIG_NAME GND\g
J 0
(-3940 3085);
DISPLAY 0.659574 (-3940 3085);
PAINT MONO (-3940 3085);
DISPLAY INVISIBLE (-3940 3085);
FORCEPROP 2 LAST CDS_LIB mstr_symbols
J 0
(-3950 3025);
PAINT MONO (-3950 3025);
DISPLAY INVISIBLE (-3950 3025);
FORCEPROP 1 LAST PATH I63
J 0
(-3875 3025);
DISPLAY 0.872340 (-3875 3025);
PAINT AQUA (-3875 3025);
DISPLAY INVISIBLE (-3875 3025);
FORCEPROP 1 LAST HDL_POWER GND
J 0
(-3950 3175);
DISPLAY 1.723404 (-3950 3175);
PAINT GREEN (-3950 3175);
DISPLAY INVISIBLE (-3950 3175);
FORCEPROP 1 LAST VOLTAGE 0
J 0
(-3950 3025);
PAINT SKYBLUE (-3950 3025);
DISPLAY INVISIBLE (-3950 3025);
FORCEPROP 1 LAST SIZE 1B
J 0
(-3875 2975);
DISPLAY 1.723404 (-3875 2975);
PAINT GREEN (-3875 2975);
DISPLAY INVISIBLE (-3875 2975);
FORCEPROP 2 LAST BOM_COST PROC_VRD_VCCIN_CPU0
J 0
(-4325 3100);
DISPLAY 1.446809 (-4325 3100);
PAINT MONO (-4325 3100);
DISPLAY INVISIBLE (-4325 3100);
FORCEPROP 2 LAST ROOM PVCCIN_CPU0_PWR_VR
J 0
(-4500 3100);
DISPLAY 1.936170 (-4500 3100);
PAINT ORANGE (-4500 3100);
DISPLAY INVISIBLE (-4500 3100);
FORCEPROP 1 LAST BODY_TYPE PLUMBING
J 0
(-3995 2982);
DISPLAY 0.340426 (-3995 2982);
PAINT GREEN (-3995 2982);
DISPLAY INVISIBLE (-3995 2982);
FORCEADD SC2K2P50V3KX-GP..1
(-2400 3300);
FORCEPROP 1 LAST LOCATION CT14
J 0
(-2375 3330);
DISPLAY 0.617021 (-2375 3330);
PAINT GREEN (-2375 3330);
FORCEPROP 0 LAST STATUS NOPOP
J 0
(-2275 3325);
DISPLAY 1.021277 (-2275 3325);
PAINT ORANGE (-2275 3325);
FORCEPROP 1 LAST VALUE SC2K2P50V3KX-GP
J 0
(-2375 3250);
DISPLAY 0.617021 (-2375 3250);
PAINT GREEN (-2375 3250);
FORCEPROP 2 LAST CDS_LIB w_hdl
J 0
(-2400 3300);
PAINT MONO (-2400 3300);
DISPLAY INVISIBLE (-2400 3300);
FORCEPROP 1 LAST PATH I64
J 0
(-2400 3300);
DISPLAY 0.617021 (-2400 3300);
PAINT GREEN (-2400 3300);
DISPLAY INVISIBLE (-2400 3300);
FORCEPROP 1 LAST CDS_LMAN_SYM_OUTLINE -50,25,50,-25
J 0
(-2400 3300);
DISPLAY 0.468085 (-2400 3300);
PAINT GREEN (-2400 3300);
DISPLAY INVISIBLE (-2400 3300);
FORCEPROP 1 LAST PACK_TYPE SMD-BCG6
J 0
(-2400 3300);
DISPLAY 0.617021 (-2400 3300);
PAINT GREEN (-2400 3300);
DISPLAY INVISIBLE (-2400 3300);
FORCEPROP 1 LAST PART_NUMBER 78.22224.2BL
J 0
(-2400 3300);
DISPLAY 0.617021 (-2400 3300);
PAINT GREEN (-2400 3300);
DISPLAY INVISIBLE (-2400 3300);
FORCEADD GND..1
(-2400 2800);
FORCEPROP 3 LASTPIN (-2400 2850) SIG_NAME GND\g
J 0
(-2390 2860);
DISPLAY 0.659574 (-2390 2860);
PAINT MONO (-2390 2860);
DISPLAY INVISIBLE (-2390 2860);
FORCEPROP 2 LAST ROOM PVCCIN_CPU0_PWR_VR
J 0
(-2950 2875);
DISPLAY 1.936170 (-2950 2875);
PAINT ORANGE (-2950 2875);
DISPLAY INVISIBLE (-2950 2875);
FORCEPROP 2 LAST BOM_COST PROC_VRD_VCCIN_CPU0
J 0
(-2775 2875);
DISPLAY 1.446809 (-2775 2875);
PAINT MONO (-2775 2875);
DISPLAY INVISIBLE (-2775 2875);
FORCEPROP 1 LAST BODY_TYPE PLUMBING
J 0
(-2445 2757);
DISPLAY 0.340426 (-2445 2757);
PAINT GREEN (-2445 2757);
DISPLAY INVISIBLE (-2445 2757);
FORCEPROP 1 LAST VOLTAGE 0
J 0
(-2400 2800);
PAINT SKYBLUE (-2400 2800);
DISPLAY INVISIBLE (-2400 2800);
FORCEPROP 1 LAST SIZE 1B
J 0
(-2325 2750);
DISPLAY 1.723404 (-2325 2750);
PAINT GREEN (-2325 2750);
DISPLAY INVISIBLE (-2325 2750);
FORCEPROP 1 LAST HDL_POWER GND
J 0
(-2400 2950);
DISPLAY 1.723404 (-2400 2950);
PAINT GREEN (-2400 2950);
DISPLAY INVISIBLE (-2400 2950);
FORCEPROP 1 LAST PATH I65
J 0
(-2325 2800);
DISPLAY 0.872340 (-2325 2800);
PAINT AQUA (-2325 2800);
DISPLAY INVISIBLE (-2325 2800);
FORCEPROP 2 LAST CDS_LIB mstr_symbols
J 0
(-2400 2800);
PAINT MONO (-2400 2800);
DISPLAY INVISIBLE (-2400 2800);
FORCEADD 3D01R5F-GP..1
R 4
(-2400 3025);
FORCEPROP 1 LAST LOCATION RT10
J 0
(-2550 3070);
DISPLAY 0.617021 (-2550 3070);
PAINT GREEN (-2550 3070);
FORCEPROP 0 LAST STATUS NOPOP
J 0
(-2325 3000);
DISPLAY 1.021277 (-2325 3000);
PAINT ORANGE (-2325 3000);
FORCEPROP 1 LAST VALUE 3D01R5F-GP
J 0
(-2350 3075);
DISPLAY 0.617021 (-2350 3075);
PAINT GREEN (-2350 3075);
FORCEPROP 2 LASTPIN (-2400 3150) SIG_NAME UN$209$3D01R5F-GP$I66$2
J 0
(-2390 3160);
DISPLAY 0.659574 (-2390 3160);
PAINT MONO (-2390 3160);
DISPLAY INVISIBLE (-2390 3160);
FORCEPROP 1 LAST PACK_TYPE SMD-RG5
R 2
J 0
(-2400 3025);
DISPLAY 0.617021 (-2400 3025);
PAINT GREEN (-2400 3025);
DISPLAY INVISIBLE (-2400 3025);
FORCEPROP 1 LAST PART_NUMBER 64.3R015.16L
R 2
J 0
(-2400 3025);
DISPLAY 0.617021 (-2400 3025);
PAINT GREEN (-2400 3025);
DISPLAY INVISIBLE (-2400 3025);
FORCEPROP 2 LAST CDS_LIB w_hdl
J 0
(-2400 3025);
PAINT MONO (-2400 3025);
DISPLAY INVISIBLE (-2400 3025);
FORCEPROP 1 LAST CDS_LMAN_SYM_OUTLINE -50,75,50,-75
R 2
J 0
(-2400 3025);
DISPLAY 0.468085 (-2400 3025);
PAINT GREEN (-2400 3025);
DISPLAY INVISIBLE (-2400 3025);
FORCEPROP 1 LAST PATH I66
R 2
J 0
(-2400 3025);
DISPLAY 0.617021 (-2400 3025);
PAINT GREEN (-2400 3025);
DISPLAY INVISIBLE (-2400 3025);
FORCEADD CAP..1
(-1950 3825);
FORCEPROP 1 LAST VALUE 1000PF
J 0
(-1900 3875);
DISPLAY 0.617021 (-1900 3875);
PAINT SKYBLUE (-1900 3875);
FORCEPROP 1 LAST VOLTAGE 50V
J 0
(-1900 3825);
DISPLAY 0.617021 (-1900 3825);
PAINT SKYBLUE (-1900 3825);
FORCEPROP 1 LAST PART_NUMBER A36096-046
J 0
(-1900 3675);
DISPLAY 0.617021 (-1900 3675);
PAINT BLUE (-1900 3675);
FORCEPROP 1 LAST MATERIAL X7R
J 0
(-1900 3725);
DISPLAY 0.617021 (-1900 3725);
PAINT SKYBLUE (-1900 3725);
FORCEPROP 0 LAST STATUS NOPOP
J 0
(-2175 3725);
DISPLAY 1.021277 (-2175 3725);
PAINT ORANGE (-2175 3725);
FORCEPROP 1 LAST LOCATION CT15
J 0
(-2100 3825);
DISPLAY 0.617021 (-2100 3825);
PAINT AQUA (-2100 3825);
FORCEPROP 1 LAST PACK_TYPE 0402LF
J 0
(-1900 3625);
DISPLAY 0.617021 (-1900 3625);
PAINT SKYBLUE (-1900 3625);
FORCEPROP 1 LAST TOLERANCE 10%
J 0
(-1900 3775);
DISPLAY 0.617021 (-1900 3775);
PAINT SKYBLUE (-1900 3775);
FORCEPROP 1 LASTPIN (-1950 3925) $PN 1
J 0
(-1940 3905);
DISPLAY 0.787234 (-1940 3905);
PAINT ORANGE (-1940 3905);
DISPLAY INVISIBLE (-1940 3905);
FORCEPROP 1 LASTPIN (-1950 3725) $PN 2
J 0
(-1940 3705);
DISPLAY 0.787234 (-1940 3705);
PAINT ORANGE (-1940 3705);
DISPLAY INVISIBLE (-1940 3705);
FORCEPROP 2 LAST CDS_LIB mstr_discrete
J 0
(-1950 3825);
PAINT MONO (-1950 3825);
DISPLAY INVISIBLE (-1950 3825);
FORCEPROP 1 LAST PATH I67
J 0
(-1900 3975);
DISPLAY 0.978723 (-1900 3975);
PAINT WHITE (-1900 3975);
DISPLAY INVISIBLE (-1900 3975);
FORCEPROP 0 LAST ROOM VDDQ_KLM_PWR_VR
J 0
(-1900 4025);
DISPLAY 1.021277 (-1900 4025);
PAINT ORANGE (-1900 4025);
DISPLAY INVISIBLE (-1900 4025);
FORCEADD GND..1
(-1950 3575);
FORCEPROP 3 LASTPIN (-1950 3625) SIG_NAME GND\g
J 0
(-1940 3635);
DISPLAY 0.659574 (-1940 3635);
PAINT MONO (-1940 3635);
DISPLAY INVISIBLE (-1940 3635);
FORCEPROP 2 LAST CDS_LIB mstr_symbols
J 0
(-1950 3575);
PAINT MONO (-1950 3575);
DISPLAY INVISIBLE (-1950 3575);
FORCEPROP 1 LAST PATH I68
J 0
(-1875 3575);
DISPLAY 0.872340 (-1875 3575);
PAINT AQUA (-1875 3575);
DISPLAY INVISIBLE (-1875 3575);
FORCEPROP 1 LAST HDL_POWER GND
J 0
(-1950 3725);
DISPLAY 1.170213 (-1950 3725);
PAINT GREEN (-1950 3725);
DISPLAY INVISIBLE (-1950 3725);
FORCEPROP 1 LAST SIZE 1B
J 0
(-1875 3525);
DISPLAY 1.170213 (-1875 3525);
PAINT AQUA (-1875 3525);
DISPLAY INVISIBLE (-1875 3525);
FORCEPROP 1 LAST BODY_TYPE PLUMBING
J 0
(-1995 3532);
DISPLAY 0.340426 (-1995 3532);
PAINT GREEN (-1995 3532);
DISPLAY INVISIBLE (-1995 3532);
FORCEPROP 1 LAST VOLTAGE 0
J 0
(-1950 3575);
PAINT SKYBLUE (-1950 3575);
DISPLAY INVISIBLE (-1950 3575);
FORCEPROP 2 LAST ROOM VDDQ_KLM_PWR_VR
J 0
(-2525 3650);
DISPLAY 1.361702 (-2525 3650);
PAINT ORANGE (-2525 3650);
DISPLAY INVISIBLE (-2525 3650);
FORCEADD RES..1
(-4800 3575);
FORCEPROP 1 LAST WATTAGE 1/16W
J 2
(-4825 3425);
DISPLAY 0.617021 (-4825 3425);
PAINT SKYBLUE (-4825 3425);
FORCEPROP 1 LAST VALUE 0.0
J 2
(-4825 3475);
DISPLAY 0.617021 (-4825 3475);
PAINT SKYBLUE (-4825 3475);
FORCEPROP 1 LAST TOLERANCE 5%
J 0
(-4800 3475);
DISPLAY 0.617021 (-4800 3475);
PAINT SKYBLUE (-4800 3475);
FORCEPROP 1 LAST MATERIAL CHIP
J 0
(-4800 3425);
DISPLAY 0.617021 (-4800 3425);
PAINT SKYBLUE (-4800 3425);
FORCEPROP 1 LAST PACK_TYPE 0402
J 0
(-4700 3425);
DISPLAY 0.617021 (-4700 3425);
PAINT SKYBLUE (-4700 3425);
FORCEPROP 1 LAST PART_NUMBER G21497-005
J 0
(-4900 3525);
DISPLAY 0.617021 (-4900 3525);
PAINT BLUE (-4900 3525);
FORCEPROP 1 LAST LOCATION RT9
J 0
(-4875 3600);
DISPLAY 0.617021 (-4875 3600);
PAINT AQUA (-4875 3600);
FORCEPROP 2 LAST CDS_LIB mstr_discrete
J 0
(-4800 3575);
PAINT MONO (-4800 3575);
DISPLAY INVISIBLE (-4800 3575);
FORCEPROP 1 LAST PATH I69
J 0
(-4850 3725);
DISPLAY 0.978723 (-4850 3725);
PAINT WHITE (-4850 3725);
DISPLAY INVISIBLE (-4850 3725);
FORCEPROP 2 LAST ROOM BMC_DEBUG_HEADER
J 0
(-4850 3725);
DISPLAY 1.021277 (-4850 3725);
PAINT ORANGE (-4850 3725);
DISPLAY INVISIBLE (-4850 3725);
FORCEPROP 2 LAST BOM_COST DEBUG
J 0
(-4850 3775);
DISPLAY 1.021277 (-4850 3775);
PAINT ORANGE (-4850 3775);
DISPLAY INVISIBLE (-4850 3775);
FORCEPROP 1 LASTPIN (-4900 3575) $PN 1
J 0
(-4888 3587);
DISPLAY 0.787234 (-4888 3587);
PAINT ORANGE (-4888 3587);
DISPLAY INVISIBLE (-4888 3587);
FORCEPROP 1 LASTPIN (-4700 3575) $PN 2
J 0
(-4738 3587);
DISPLAY 0.787234 (-4738 3587);
PAINT ORANGE (-4738 3587);
DISPLAY INVISIBLE (-4738 3587);
FORCEADD CAP..1
(-6900 4025);
FORCEPROP 1 LAST LOCATION C9N26
J 0
(-6850 4125);
DISPLAY 0.617021 (-6850 4125);
PAINT AQUA (-6850 4125);
FORCEPROP 1 LASTPIN (-6900 4125) $PN 1
J 0
(-6890 4105);
DISPLAY 0.617021 (-6890 4105);
PAINT ORANGE (-6890 4105);
FORCEPROP 1 LAST VALUE 10UF
J 0
(-6850 4075);
DISPLAY 0.617021 (-6850 4075);
PAINT SKYBLUE (-6850 4075);
FORCEPROP 1 LAST PART_NUMBER C95333-007
J 0
(-6850 3875);
DISPLAY 0.617021 (-6850 3875);
PAINT BLUE (-6850 3875);
FORCEPROP 1 LAST TOLERANCE 10%
J 0
(-6850 3975);
DISPLAY 0.617021 (-6850 3975);
PAINT SKYBLUE (-6850 3975);
FORCEPROP 1 LAST PACK_TYPE 0805
J 0
(-6850 3825);
DISPLAY 0.617021 (-6850 3825);
PAINT SKYBLUE (-6850 3825);
FORCEPROP 1 LAST VOLTAGE 16V
J 0
(-6850 4025);
DISPLAY 0.617021 (-6850 4025);
PAINT SKYBLUE (-6850 4025);
FORCEPROP 1 LAST MATERIAL X6S
J 0
(-6850 3925);
DISPLAY 0.617021 (-6850 3925);
PAINT SKYBLUE (-6850 3925);
FORCEPROP 1 LASTPIN (-6900 3925) $PN 2
J 0
(-6890 3905);
DISPLAY 0.617021 (-6890 3905);
PAINT ORANGE (-6890 3905);
FORCEPROP 2 LAST SEC_TYPE 0805
J 0
(-6850 4225);
DISPLAY 1.021277 (-6850 4225);
PAINT ORANGE (-6850 4225);
DISPLAY INVISIBLE (-6850 4225);
FORCEPROP 2 LAST SEC 1
J 0
(-6850 4225);
DISPLAY 0.680851 (-6850 4225);
PAINT MONO (-6850 4225);
DISPLAY INVISIBLE (-6850 4225);
FORCEPROP 1 LAST PATH I7
J 0
(-6850 4175);
DISPLAY 0.978723 (-6850 4175);
PAINT WHITE (-6850 4175);
DISPLAY INVISIBLE (-6850 4175);
FORCEPROP 2 LAST ROOM PVCCIN_CPU1_PWR_VR
J 0
(-6850 4175);
DISPLAY 1.361702 (-6850 4175);
PAINT ORANGE (-6850 4175);
DISPLAY INVISIBLE (-6850 4175);
FORCEPROP 2 LAST CDS_LIB mstr_discrete
J 0
(-6900 4025);
PAINT ORANGE (-6900 4025);
DISPLAY INVISIBLE (-6900 4025);
FORCEADD CAP..1
(-6625 3975);
FORCEPROP 1 LAST LOCATION C9N25
J 0
(-6575 4075);
DISPLAY 0.617021 (-6575 4075);
PAINT AQUA (-6575 4075);
FORCEPROP 1 LAST PART_NUMBER C95333-007
J 0
(-6575 3825);
DISPLAY 0.617021 (-6575 3825);
PAINT BLUE (-6575 3825);
FORCEPROP 1 LASTPIN (-6625 4075) $PN 1
J 0
(-6615 4055);
DISPLAY 0.617021 (-6615 4055);
PAINT ORANGE (-6615 4055);
FORCEPROP 1 LASTPIN (-6625 3875) $PN 2
J 0
(-6615 3855);
DISPLAY 0.617021 (-6615 3855);
PAINT ORANGE (-6615 3855);
FORCEPROP 1 LAST MATERIAL X6S
J 0
(-6575 3875);
DISPLAY 0.617021 (-6575 3875);
PAINT SKYBLUE (-6575 3875);
FORCEPROP 1 LAST VOLTAGE 16V
J 0
(-6575 3975);
DISPLAY 0.617021 (-6575 3975);
PAINT SKYBLUE (-6575 3975);
FORCEPROP 1 LAST TOLERANCE 10%
J 0
(-6575 3925);
DISPLAY 0.617021 (-6575 3925);
PAINT SKYBLUE (-6575 3925);
FORCEPROP 1 LAST VALUE 10UF
J 0
(-6575 4025);
DISPLAY 0.617021 (-6575 4025);
PAINT SKYBLUE (-6575 4025);
FORCEPROP 1 LAST PACK_TYPE 0805
J 0
(-6575 3775);
DISPLAY 0.617021 (-6575 3775);
PAINT SKYBLUE (-6575 3775);
FORCEPROP 2 LAST SEC_TYPE 0805
J 0
(-6575 4175);
DISPLAY 1.021277 (-6575 4175);
PAINT ORANGE (-6575 4175);
DISPLAY INVISIBLE (-6575 4175);
FORCEPROP 2 LAST SEC 1
J 0
(-6575 4175);
DISPLAY 0.680851 (-6575 4175);
PAINT MONO (-6575 4175);
DISPLAY INVISIBLE (-6575 4175);
FORCEPROP 1 LAST PATH I8
J 0
(-6575 4125);
DISPLAY 0.978723 (-6575 4125);
PAINT WHITE (-6575 4125);
DISPLAY INVISIBLE (-6575 4125);
FORCEPROP 2 LAST ROOM PVCCIN_CPU1_PWR_VR
J 0
(-6575 4125);
DISPLAY 1.361702 (-6575 4125);
PAINT ORANGE (-6575 4125);
DISPLAY INVISIBLE (-6575 4125);
FORCEPROP 2 LAST CDS_LIB mstr_discrete
J 0
(-6625 3975);
PAINT ORANGE (-6625 3975);
DISPLAY INVISIBLE (-6625 3975);
FORCEADD RES..1
(-5475 1050);
FORCEPROP 1 LAST PART_NUMBER G21796-017
J 0
(-5525 1150);
DISPLAY 0.617021 (-5525 1150);
PAINT BLUE (-5525 1150);
FORCEPROP 1 LASTPIN (-5375 1050) $PN 2
J 0
(-5413 1062);
DISPLAY 0.617021 (-5413 1062);
PAINT GREEN (-5413 1062);
FORCEPROP 1 LAST LOCATION R1E8
J 0
(-5525 1100);
DISPLAY 0.617021 (-5525 1100);
PAINT AQUA (-5525 1100);
FORCEPROP 1 LASTPIN (-5575 1050) $PN 1
J 0
(-5563 1062);
DISPLAY 0.617021 (-5563 1062);
PAINT GREEN (-5563 1062);
FORCEPROP 1 LAST VALUE 100.0
J 2
(-5475 975);
DISPLAY 0.617021 (-5475 975);
PAINT SKYBLUE (-5475 975);
FORCEPROP 1 LAST TOLERANCE 1%
J 0
(-5425 975);
DISPLAY 0.617021 (-5425 975);
PAINT SKYBLUE (-5425 975);
FORCEPROP 1 LAST PACK_TYPE 0402
J 0
(-5550 875);
DISPLAY 0.617021 (-5550 875);
PAINT SKYBLUE (-5550 875);
FORCEPROP 1 LAST WATTAGE 1/16W
J 2
(-5475 925);
DISPLAY 0.617021 (-5475 925);
PAINT SKYBLUE (-5475 925);
FORCEPROP 2 LAST CDS_SEC 1
J 0
(-5525 1250);
PAINT MONO (-5525 1250);
DISPLAY INVISIBLE (-5525 1250);
FORCEPROP 2 LAST $SEC 1
J 0
(-5525 1250);
PAINT MONO (-5525 1250);
DISPLAY INVISIBLE (-5525 1250);
FORCEPROP 2 LAST CDS_LIB mstr_discrete
J 0
(-5475 1050);
PAINT ORANGE (-5475 1050);
DISPLAY INVISIBLE (-5475 1050);
FORCEPROP 1 LAST PATH I9
J 0
(-5525 1200);
DISPLAY 0.978723 (-5525 1200);
PAINT WHITE (-5525 1200);
DISPLAY INVISIBLE (-5525 1200);
FORCEPROP 2 LAST CDS_LOCATION R1E8
J 0
(-5525 1100);
DISPLAY 0.617021 (-5525 1100);
PAINT AQUA (-5525 1100);
DISPLAY INVISIBLE (-5525 1100);
FORCEPROP 2 LAST BOM_COST PROC_VRD_VCCIN_CPU0
J 0
(-5525 1200);
PAINT MONO (-5525 1200);
DISPLAY INVISIBLE (-5525 1200);
FORCEPROP 2 LAST ROOM PVCCIN_CPU1_VSENSE_VR
J 0
(-5525 1150);
PAINT ORANGE (-5525 1150);
DISPLAY INVISIBLE (-5525 1150);
FORCEPROP 1 LAST MATERIAL CHIP
J 0
(-5450 925);
PAINT SKYBLUE (-5450 925);
DISPLAY INVISIBLE (-5450 925);
FORCEADD DESIGN_NOTE..1
(-7550 2950);
PAINT PURPLE (-7550 2950);
FORCEPROP 1 LAST COMMENT_BODY TRUE
J 0
(-7525 3050);
DISPLAY 1.319149 (-7525 3050);
PAINT GREEN (-7525 3050);
DISPLAY INVISIBLE (-7525 3050);
FORCEPROP 2 LAST CDS_LIB mstr_symbols
J 0
(-7550 2950);
PAINT ORANGE (-7550 2950);
DISPLAY INVISIBLE (-7550 2950);
FORCEPROP 2 LAST ROOM PVCCIN_CPU0_VR
J 0
(-7750 2900);
PAINT MONO (-7750 2900);
DISPLAY INVISIBLE (-7750 2900);
FORCEPROP 2 LAST BOM_COST SM_CONTROLLER
J 0
(-7750 2900);
PAINT MONO (-7750 2900);
DISPLAY INVISIBLE (-7750 2900);
FORCEADD DNS..2
(-6295 1695);
PAINT RED (-6295 1695);
FORCEPROP 2 LAST CDS_LIB mstr_misc
J 0
(-6295 1695);
PAINT ORANGE (-6295 1695);
DISPLAY INVISIBLE (-6295 1695);
FORCEPROP 1 LAST COMMENT_BODY TRUE
R 1
J 0
(-6220 1470);
DISPLAY 0.872340 (-6220 1470);
PAINT GREEN (-6220 1470);
DISPLAY INVISIBLE (-6220 1470);
FORCEADD DNS..7
(-2770 1345);
PAINT RED (-2770 1345);
FORCEPROP 2 LAST CDS_LIB mstr_misc
J 0
(-2770 1345);
PAINT ORANGE (-2770 1345);
DISPLAY INVISIBLE (-2770 1345);
FORCEPROP 1 LAST COMMENT_BODY TRUE
R 1
J 0
(-2695 1120);
DISPLAY 0.872340 (-2695 1120);
PAINT GREEN (-2695 1120);
DISPLAY INVISIBLE (-2695 1120);
FORCEADD DNS..2
(-2245 1120);
PAINT RED (-2245 1120);
FORCEPROP 2 LAST CDS_LIB mstr_misc
J 0
(-2245 1120);
PAINT ORANGE (-2245 1120);
DISPLAY INVISIBLE (-2245 1120);
FORCEPROP 1 LAST COMMENT_BODY TRUE
R 1
J 0
(-2170 895);
DISPLAY 0.872340 (-2170 895);
PAINT GREEN (-2170 895);
DISPLAY INVISIBLE (-2170 895);
FORCEADD DNS..2
(-995 3920);
PAINT RED (-995 3920);
FORCEPROP 2 LAST CDS_LIB mstr_misc
J 0
(-995 3920);
PAINT ORANGE (-995 3920);
DISPLAY INVISIBLE (-995 3920);
FORCEPROP 1 LAST COMMENT_BODY TRUE
R 1
J 0
(-920 3695);
DISPLAY 0.872340 (-920 3695);
PAINT GREEN (-920 3695);
DISPLAY INVISIBLE (-920 3695);
FORCEADD INTEL_CORP_BPAGE..1
(0 0);
FORCEPROP 1 LAST CDS_CON_LAST_MODIFIED Tue Dec 01 11:52:23 2015
J 0
(-1425 325);
PAINT ORANGE (-1425 325);
DISPLAY INVISIBLE (-1425 325);
FORCEPROP 1 LAST CUSTOM_TXT_CDS <CURRENT_DESIGN_SHEET> OF <TOTAL_DESIGN_SHEETS>
J 0
(-500 25);
PAINT GREEN (-500 25);
FORCEPROP 1 LAST CUSTOM_TXT_CDS <CON_LAST_MODIFIED>
J 0
(-1925 350);
PAINT GREEN (-1925 350);
FORCEPROP 2 LAST CUSTOM_TXT_CDS <XR_PAGE_TITLE>
J 0
(-7890 5250);
DISPLAY 0.638298 (-7890 5250);
PAINT PINK (-7890 5250);
DISPLAY INVISIBLE (-7890 5250);
FORCEPROP 1 LAST SCH_DEPT BESD
J 1
(-4450 100);
DISPLAY 1.212766 (-4450 100);
PAINT YELLOW (-4450 100);
FORCEPROP 1 LAST SCH_REV 2.420
J 0
(-250 150);
DISPLAY 0.978723 (-250 150);
PAINT YELLOW (-250 150);
FORCEPROP 1 LAST SCH_NUMBER H4694802
J 0
(-1300 150);
DISPLAY 1.212766 (-1300 150);
PAINT YELLOW (-1300 150);
FORCEPROP 1 LAST SCH_ADDRESS2 P.O. BOX 58119
J 0
(-3975 75);
DISPLAY 0.617021 (-3975 75);
PAINT GREEN (-3975 75);
FORCEPROP 1 LAST SCH_ADDRESS1 2200 Mission College Blvd.
J 0
(-3975 125);
DISPLAY 0.617021 (-3975 125);
PAINT GREEN (-3975 125);
FORCEPROP 1 LAST SCH_TITLE VCCIN CPU1 (4 OF 4)
J 0
(-7950 50);
DISPLAY 1.212766 (-7950 50);
PAINT ORANGE (-7950 50);
FORCEPROP 1 LAST SCH_ADDRESS3 Santa Clara, CA 95052-8119
J 0
(-3975 25);
DISPLAY 0.617021 (-3975 25);
PAINT GREEN (-3975 25);
FORCEPROP 1 LAST COMMENT_BODY TRUE
J 0
(12 12);
DISPLAY 0.468085 (12 12);
PAINT GREEN (12 12);
DISPLAY INVISIBLE (12 12);
FORCEPROP 2 LAST CDS_LIB mstr_symbols
J 0
(0 0);
PAINT ORANGE (0 0);
DISPLAY INVISIBLE (0 0);
FORCEPROP 2 LAST PAGE_BORDER TRUE
J 0
(-7890 5250);
DISPLAY 0.638298 (-7890 5250);
PAINT PINK (-7890 5250);
DISPLAY INVISIBLE (-7890 5250);
FORCEPROP 2 LAST CDS_XR_PAGE_TITLE CR-209 : @BASEBOARD_FAB2_LIB.BASEBOARD_FAB2(SCH_1):PAGE209
J 0
(-7890 5250);
DISPLAY 0.638298 (-7890 5250);
PAINT PINK (-7890 5250);
DISPLAY INVISIBLE (-7890 5250);
WIRE 16 -1 (-4825 825)(-4825 1050);
WIRE 16 -1 (-4825 1050)(-5375 1050);
WIRE 16 -1 (-5400 2300)(-4650 2300);
WIRE 16 -1 (-4650 2300)(-4650 2400);
WIRE 16 -1 (-3750 4225)(-3875 4225);
WIRE 16 -1 (-3875 4225)(-3875 4275);
WIRE 16 -1 (-3875 4275)(-3750 4275);
WIRE 16 -1 (-3875 4275)(-6000 4275);
WIRE 16 -1 (-6000 4150)(-6000 4275);
WIRE 16 -1 (-6350 4275)(-6000 4275);
WIRE 16 -1 (-6350 4125)(-6350 4275);
WIRE 16 -1 (-6350 4275)(-6625 4275);
WIRE 16 -1 (-6625 4075)(-6625 4275);
WIRE 16 -1 (-6625 4275)(-6900 4275);
WIRE 16 -1 (-6900 4125)(-6900 4275);
WIRE 16 -1 (-6900 4275)(-7175 4275);
WIRE 16 -1 (-7175 4125)(-7175 4275);
WIRE 16 -1 (-7175 4475)(-7175 4275);
WIRE 16 -1 (-3125 1250)(-3300 1250);
WIRE 16 -1 (-3300 1250)(-3300 1200);
WIRE 16 -1 (-3125 1200)(-3300 1200);
WIRE 16 -1 (-3300 1200)(-3300 1050);
WIRE 16 -1 (-2250 1025)(-2250 900);
WIRE 16 -1 (-2750 3375)(-2675 3375);
WIRE 16 -1 (-2675 3325)(-2675 3375);
WIRE 16 -1 (-2675 3275)(-2675 3325);
WIRE 16 -1 (-2675 3325)(-2750 3325);
WIRE 16 -1 (-2675 3225)(-2675 3275);
WIRE 16 -1 (-2675 3275)(-2750 3275);
WIRE 16 -1 (-2675 3175)(-2675 3225);
WIRE 16 -1 (-2675 3225)(-2750 3225);
WIRE 16 -1 (-600 1950)(-600 1775);
WIRE 16 -1 (-600 1775)(-950 1775);
WIRE 16 -1 (-950 1950)(-950 1775);
WIRE 16 -1 (-950 1775)(-1200 1775);
WIRE 16 -1 (-1200 1775)(-1425 1775);
WIRE 16 -1 (-1200 1700)(-1200 1775);
WIRE 16 -1 (-1425 1975)(-1425 1775);
WIRE 16 -1 (-4875 3950)(-4875 3750);
WIRE 16 -1 (-4875 3750)(-4975 3750);
WIRE 16 -1 (-4975 3950)(-4975 3750);
WIRE 16 -1 (-4975 3750)(-5625 3750);
WIRE 16 -1 (-5625 3925)(-5625 3750);
WIRE 16 -1 (-5625 3750)(-6000 3750);
WIRE 16 -1 (-6000 3950)(-6000 3750);
WIRE 16 -1 (-6350 3750)(-6000 3750);
WIRE 16 -1 (-6350 3925)(-6350 3750);
WIRE 16 -1 (-6350 3750)(-6625 3750);
WIRE 16 -1 (-6625 3875)(-6625 3750);
WIRE 16 -1 (-6625 3750)(-6900 3750);
WIRE 16 -1 (-6900 3925)(-6900 3750);
WIRE 16 -1 (-6900 3750)(-7175 3750);
WIRE 16 -1 (-7175 3925)(-7175 3750);
WIRE 16 -1 (-7175 3550)(-7175 3750);
WIRE 16 -1 (-750 3000)(-750 3125);
WIRE 16 -1 (-375 3000)(-750 3000);
WIRE 16 -1 (-375 3150)(-375 3000);
WIRE 16 -1 (-375 2900)(-375 3000);
WIRE 16 -1 (-3750 3925)(-3825 3925);
WIRE 16 -1 (-3825 3925)(-3825 2775);
WIRE 16 -1 (-3825 2775)(-1075 2775);
WIRE 16 -1 (-1075 2775)(-1075 3475);
WIRE 16 -1 (-1350 3475)(-1075 3475);
WIRE 16 -1 (-1075 3475)(-750 3475);
WIRE 16 -1 (-750 3325)(-750 3475);
WIRE 16 -1 (-750 3475)(-375 3475);
WIRE 16 -1 (-375 3350)(-375 3475);
WIRE 16 -1 (-225 3475)(-375 3475);
WIRE 16 -1 (-225 3475)(-225 3600);
WIRE 16 -1 (-1625 1300)(-1625 2250);
WIRE 16 -1 (-1625 1300)(-2425 1300);
WIRE 16 -1 (-1750 2250)(-1625 2250);
WIRE 16 -1 (-1625 2250)(-1425 2250);
WIRE 16 -1 (-1425 2175)(-1425 2250);
WIRE 16 -1 (-1425 2250)(-950 2250);
WIRE 16 -1 (-950 2150)(-950 2250);
WIRE 16 -1 (-600 2250)(-950 2250);
WIRE 16 -1 (-600 2150)(-600 2250);
WIRE 16 -1 (-600 2475)(-600 2250);
WIRE 16 -1 (-3100 2250)(-3350 2250);
WIRE 16 -1 (-3350 2425)(-3350 2250);
WIRE 16 -1 (-4025 4125)(-4025 4025);
WIRE 16 -1 (-4025 4650)(-4025 4125);
WIRE 16 -1 (-4025 4125)(-3750 4125);
WIRE 16 -1 (-4025 4025)(-3750 4025);
WIRE 16 -1 (-4025 4650)(-4550 4650);
WIRE 16 -1 (-4550 4650)(-4875 4650);
WIRE 16 -1 (-4550 4650)(-4550 4700);
WIRE 16 -1 (-4875 4650)(-4975 4650);
WIRE 16 -1 (-4875 4150)(-4875 4650);
WIRE 16 -1 (-4975 4150)(-4975 4650);
WIRE 16 -1 (-4975 4650)(-5200 4650);
WIRE 16 -1 (-1000 3725)(-1000 3825);
WIRE 16 -1 (-3950 3175)(-3950 3075);
WIRE 16 -1 (-2400 2900)(-2400 2850);
WIRE 16 -1 (-1950 3725)(-1950 3625);
WIRE 3 2175 (-2200 3550)(-1725 3550);
WIRE 3 2175 (-2200 4025)(-2200 3550);
WIRE 3 2175 (-1725 4025)(-1725 3550);
WIRE 3 2175 (-2200 4025)(-1725 4025);
WIRE 16 -1 (-2750 3975)(-1950 3975);
FORCEPROP 2 LAST SIG_NAME A_TSENSE_PVCCIN_CPU1
J 0
(-2718 3995);
DISPLAY 0.617021 (-2718 3995);
PAINT ORANGE (-2718 3995);
WIRE 16 -1 (-2750 3975)(-2750 3825);
WIRE 16 -1 (-1950 3975)(-1750 3975);
WIRE 16 -1 (-1950 3925)(-1950 3975);
WIRE 16 -1 (-1550 3475)(-2400 3475);
WIRE 16 -1 (-2400 3375)(-2400 3475);
WIRE 16 -1 (-2400 3475)(-2750 3475);
FORCEPROP 0 LAST VOLTAGE 5
J 0
(-2500 3550);
DISPLAY 1.021277 (-2500 3550);
PAINT SKYBLUE (-2500 3550);
DISPLAY INVISIBLE (-2500 3550);
FORCEPROP 2 LAST SIG_NAME VR_PVCCIN_CPU1_PHASE5
J 0
(-2515 3485);
DISPLAY 0.617021 (-2515 3485);
PAINT ORANGE (-2515 3485);
FORCEPROP 2 LASTPROP $XRERR UNIQUE?
J 0
(-2755 3485);
DISPLAY 0.638298 (-2755 3485);
PAINT MONO (-2755 3485);
DISPLAY INVISIBLE (-2755 3485);
WIRE 3 2175 (-2575 3400)(-2050 3400);
WIRE 3 2175 (-2575 3400)(-2575 2725);
WIRE 3 2175 (-2050 3400)(-2050 2725);
WIRE 3 2175 (-2575 2725)(-2050 2725);
WIRE 16 -1 (-2400 3225)(-2400 3150);
WIRE 16 -1 (-5575 3350)(-4050 3350);
FORCEPROP 0 LAST VOLTAGE 5
J 0
(-5475 3425);
DISPLAY 1.021277 (-5475 3425);
PAINT SKYBLUE (-5475 3425);
DISPLAY INVISIBLE (-5475 3425);
FORCEPROP 2 LAST SIG_NAME VR_PVCCIN_CPU1_PH5_PHASE
J 0
(-5490 3360);
DISPLAY 0.617021 (-5490 3360);
PAINT ORANGE (-5490 3360);
FORCEPROP 2 LASTPROP $XRERR UNIQUE?
J 0
(-5730 3360);
DISPLAY 0.638298 (-5730 3360);
PAINT MONO (-5730 3360);
DISPLAY INVISIBLE (-5730 3360);
WIRE 16 -1 (-4050 3350)(-4050 3425);
WIRE 16 -1 (-4050 3425)(-3750 3425);
WIRE 16 -1 (-4700 3575)(-4050 3575);
FORCEPROP 2 LAST SIG_NAME VR_PVCCIN_CPU1_PH5_BOOT_R
J 0
(-4529 3572);
DISPLAY 0.617021 (-4529 3572);
PAINT ORANGE (-4529 3572);
FORCEPROP 2 LASTPROP $XRERR UNIQUE?
J 0
(-4769 3572);
DISPLAY 0.638298 (-4769 3572);
PAINT MONO (-4769 3572);
DISPLAY INVISIBLE (-4769 3572);
WIRE 16 -1 (-4050 3475)(-4050 3575);
WIRE 16 -1 (-4050 3475)(-3750 3475);
WIRE 3 2175 (-4200 3525)(-3675 3525);
WIRE 3 2175 (-4200 3525)(-4200 2975);
WIRE 3 2175 (-3675 3525)(-3675 2975);
WIRE 3 2175 (-4200 2975)(-3675 2975);
WIRE 16 -1 (-4900 3575)(-5575 3575);
FORCEPROP 2 LAST SIG_NAME VR_PVCCIN_CPU1_PH5_BOOT
J 0
(-5540 3585);
DISPLAY 0.617021 (-5540 3585);
PAINT ORANGE (-5540 3585);
FORCEPROP 2 LASTPROP $XRERR UNIQUE?
J 0
(-5780 3585);
DISPLAY 0.638298 (-5780 3585);
PAINT MONO (-5780 3585);
DISPLAY INVISIBLE (-5780 3585);
WIRE 16 -1 (-5575 3575)(-5575 3550);
WIRE 16 -1 (-7575 1850)(-6850 1850);
FORCEPROP 2 LAST SIG_NAME VSENSE_PVCCIN_CPU1_P
J 0
(-7585 1860);
DISPLAY 0.617021 (-7585 1860);
PAINT ORANGE (-7585 1860);
WIRE 16 -1 (-6850 1750)(-6850 1850);
WIRE 16 -1 (-6850 1750)(-6525 1750);
WIRE 16 -1 (-6525 1750)(-6525 1900);
WIRE 16 -1 (-6525 1900)(-6300 1900);
WIRE 16 -1 (-6300 1900)(-5925 1900);
WIRE 16 -1 (-6300 1800)(-6300 1900);
WIRE 16 -1 (-5925 1900)(-5925 2300);
WIRE 16 -1 (-5925 1900)(-5600 1900);
WIRE 16 -1 (-5925 2300)(-5600 2300);
WIRE 16 682 (-7075 3025)(-7075 2275);
WIRE 16 682 (-7775 3025)(-7075 3025);
WIRE 16 682 (-7075 2275)(-7775 2275);
WIRE 16 682 (-7775 2275)(-7775 3025);
WIRE 16 -1 (-2250 1450)(-2250 2250);
WIRE 16 -1 (-2250 1225)(-2250 1450);
WIRE 16 -1 (-2250 1450)(-2425 1450);
WIRE 16 -1 (-2250 2250)(-2075 2250);
WIRE 16 -1 (-2900 2250)(-2250 2250);
FORCEPROP 2 LAST SIG_NAME VR_FET_SW_P12V_PVCCIN_CPU1_R
J 0
(-2800 2275);
DISPLAY 0.617021 (-2800 2275);
PAINT ORANGE (-2800 2275);
FORCEPROP 2 LASTPROP $XRERR UNIQUE?
J 0
(-3040 2275);
DISPLAY 0.638298 (-3040 2275);
PAINT MONO (-3040 2275);
DISPLAY INVISIBLE (-3040 2275);
WIRE 16 -1 (-2075 2250)(-1950 2250);
WIRE 16 -1 (-2075 1350)(-2075 2250);
WIRE 16 -1 (-2075 1350)(-2425 1350);
WIRE 16 -1 (-2750 4125)(-1000 4125);
FORCEPROP 0 LAST SIG_NAME VR_PVCCIN_CPU1_PH5_OCSET
J 0
(-2435 4135);
DISPLAY 0.617021 (-2435 4135);
PAINT ORANGE (-2435 4135);
FORCEPROP 2 LASTPROP $XRERR UNIQUE?
J 0
(-2675 4135);
DISPLAY 0.638298 (-2675 4135);
PAINT MONO (-2675 4135);
DISPLAY INVISIBLE (-2675 4135);
WIRE 16 -1 (-1000 4125)(-1000 4025);
WIRE 3 2175 (-5000 3400)(-4550 3400);
WIRE 3 2175 (-5000 3650)(-5000 3400);
WIRE 3 2175 (-4550 3650)(-4550 3400);
WIRE 3 2175 (-5000 3650)(-4550 3650);
WIRE 16 2175 (-5900 3625)(-5150 3625);
WIRE 16 2175 (-5900 3625)(-5900 3150);
WIRE 16 2175 (-5150 3625)(-5150 3150);
WIRE 16 2175 (-5900 3150)(-5150 3150);
WIRE 16 -1 (-6175 3675)(-3750 3675);
FORCEPROP 0 LAST VOLTAGE 3.6
J 0
(-4975 3725);
DISPLAY 1.021277 (-4975 3725);
PAINT SKYBLUE (-4975 3725);
DISPLAY INVISIBLE (-4975 3725);
WIRE 16 -1 (-3750 3775)(-4500 3775);
FORCEPROP 0 LAST SIG_NAME TP_PVCCIN_CPU1_PH5_GL_0
J 0
(-4473 3790);
DISPLAY 0.617021 (-4473 3790);
PAINT ORANGE (-4473 3790);
FORCEPROP 2 LASTPROP $XRERR UNIQUE?
J 0
(-4740 3775);
DISPLAY 0.638298 (-4740 3775);
PAINT MONO (-4740 3775);
DISPLAY INVISIBLE (-4740 3775);
WIRE 16 -1 (-3750 3575)(-3950 3575);
WIRE 16 -1 (-3950 3575)(-3950 4800);
WIRE 16 -1 (-3950 3375)(-3950 3575);
WIRE 16 -1 (-3950 4800)(-1175 4800);
FORCEPROP 2 LAST SIG_NAME VR_PVCCIN_CPU1_AIREF5
J 2
(-1215 4809);
DISPLAY 0.617021 (-1215 4809);
PAINT ORANGE (-1215 4809);
WIRE 16 -1 (-2750 4075)(-2050 4075);
FORCEPROP 2 LAST SIG_NAME NC_PVCCIN_CPU1_PH5_P31
J 0
(-2532 4089);
DISPLAY 0.617021 (-2532 4089);
PAINT ORANGE (-2532 4089);
FORCEPROP 2 LASTPROP $XRERR UNIQUE?
J 0
(-2020 4075);
DISPLAY 0.638298 (-2020 4075);
PAINT MONO (-2020 4075);
DISPLAY INVISIBLE (-2020 4075);
WIRE 16 -1 (-2750 4325)(-1200 4325);
FORCEPROP 2 LAST SIG_NAME ISENSE_PVCCIN_CPU1_PH5_IMON
J 0
(-2440 4335);
DISPLAY 0.617021 (-2440 4335);
PAINT ORANGE (-2440 4335);
WIRE 16 -1 (-5625 4125)(-5625 4325);
WIRE 16 -1 (-5625 4325)(-5575 4325);
WIRE 16 -1 (-5575 4325)(-3750 4325);
FORCEPROP 0 LAST VOLTAGE 5
J 0
(-4350 4400);
DISPLAY 1.021277 (-4350 4400);
PAINT SKYBLUE (-4350 4400);
DISPLAY INVISIBLE (-4350 4400);
FORCEPROP 2 LAST SIG_NAME VR_PVCCIN_CPU1_PH5_VCIN
J 0
(-5565 4335);
DISPLAY 0.617021 (-5565 4335);
PAINT ORANGE (-5565 4335);
FORCEPROP 2 LASTPROP $XRERR UNIQUE?
J 0
(-5805 4335);
DISPLAY 0.638298 (-5805 4335);
PAINT MONO (-5805 4335);
DISPLAY INVISIBLE (-5805 4335);
WIRE 16 -1 (-5575 4325)(-5575 4650);
WIRE 16 -1 (-5575 4650)(-5400 4650);
WIRE 16 -1 (-3750 3825)(-4500 3825);
FORCEPROP 0 LAST SIG_NAME TP_PVCCIN_CPU1_PH5_GL_1
J 0
(-4473 3840);
DISPLAY 0.617021 (-4473 3840);
PAINT ORANGE (-4473 3840);
FORCEPROP 2 LASTPROP $XRERR UNIQUE?
J 0
(-4740 3825);
DISPLAY 0.638298 (-4740 3825);
PAINT MONO (-4740 3825);
DISPLAY INVISIBLE (-4740 3825);
WIRE 16 -1 (-5400 1900)(-4350 1900);
FORCEPROP 2 LAST SIG_NAME VSENSE_PVCCIN_CPU1_SKT_VSEN
J 0
(-5223 1919);
DISPLAY 0.617021 (-5223 1919);
PAINT ORANGE (-5223 1919);
WIRE 16 -1 (-5375 1450)(-4350 1450);
FORCEPROP 2 LAST SIG_NAME VSENSE_PVCCIN_CPU1_SKT_VRTN
J 0
(-5160 1460);
DISPLAY 0.617021 (-5160 1460);
PAINT ORANGE (-5160 1460);
WIRE 16 -1 (-7575 1575)(-6850 1575);
FORCEPROP 2 LAST SIG_NAME VSENSE_PVCCIN_CPU1_N
J 0
(-7585 1585);
DISPLAY 0.617021 (-7585 1585);
PAINT ORANGE (-7585 1585);
WIRE 16 -1 (-6850 1575)(-6850 1675);
WIRE 16 -1 (-6850 1675)(-6525 1675);
WIRE 16 -1 (-6525 1675)(-6525 1450);
WIRE 16 -1 (-6525 1450)(-6300 1450);
WIRE 16 -1 (-6300 1450)(-5925 1450);
WIRE 16 -1 (-6300 1600)(-6300 1450);
WIRE 16 -1 (-5925 1450)(-5575 1450);
WIRE 16 -1 (-5925 1050)(-5925 1450);
WIRE 16 -1 (-5925 1050)(-5575 1050);
WIRE 16 2175 (-5250 4225)(-4600 4225);
WIRE 16 2175 (-5250 4225)(-5250 3825);
WIRE 16 2175 (-4600 4225)(-4600 3825);
WIRE 16 2175 (-5250 3825)(-4600 3825);
WIRE 16 273 (-6425 1400)(-6425 1975);
WIRE 16 273 (-6925 1400)(-6425 1400);
WIRE 16 273 (-6425 1975)(-6925 1975);
WIRE 16 273 (-6925 1975)(-6925 1400);
WIRE 16 -1 (-3800 1675)(-3250 1675);
FORCEPROP 2 LAST SIG_NAME PVCCIN_PVSA_CPU1_IINSEN
J 0
(-3755 1685);
DISPLAY 0.617021 (-3755 1685);
PAINT ORANGE (-3755 1685);
WIRE 16 -1 (-3250 1450)(-3250 1675);
WIRE 16 -1 (-3250 1450)(-3125 1450);
DOT 1 (-1625 2250);
DOT 1 (-950 2250);
DOT 1 (-375 3475);
DOT 1 (-1425 2250);
DOT 1 (-375 3000);
DOT 1 (-2075 2250);
DOT 1 (-1950 3975);
DOT 1 (-2400 3475);
DOT 1 (-2675 3275);
DOT 1 (-3950 3575);
DOT 1 (-6300 1450);
DOT 1 (-6300 1900);
DOT 1 (-7175 3750);
DOT 1 (-6900 3750);
DOT 1 (-6625 3750);
DOT 1 (-6350 3750);
DOT 1 (-5925 1450);
DOT 1 (-5925 1900);
DOT 1 (-6000 3750);
DOT 1 (-5625 3750);
DOT 1 (-4975 3750);
DOT 1 (-7175 4275);
DOT 1 (-6900 4275);
DOT 1 (-6625 4275);
DOT 1 (-6350 4275);
DOT 1 (-6000 4275);
DOT 1 (-5575 4325);
DOT 1 (-4875 4650);
DOT 1 (-4975 4650);
DOT 1 (-4550 4650);
DOT 1 (-3300 1200);
DOT 1 (-2250 1450);
DOT 1 (-2250 2250);
DOT 1 (-2675 3225);
DOT 1 (-2675 3325);
DOT 1 (-1200 1775);
DOT 1 (-950 1775);
DOT 1 (-1075 3475);
DOT 1 (-600 2250);
DOT 1 (-750 3475);
DOT 1 (-4025 4125);
DOT 1 (-3875 4275);
FORCENOTE
INPUT FILTER
(-2965 2415) 0;
DISPLAY LEFT (-2965 2415);
PAINT PURPLE (-2965 2415);
FORCENOTE
PLACE ON TOP
(-5255 3725) 0;
DISPLAY LEFT (-5255 3725);
DISPLAY 1.553191 (-5255 3725);
PAINT PURPLE (-5255 3725);
FORCENOTE
ROOM = PVCCIN_CPU1_VSENSE_VR
(-7190 590) 0;
DISPLAY LEFT (-7190 590);
DISPLAY 2.446809 (-7190 590);
PAINT PURPLE (-7190 590);
FORCENOTE
IOUT PK=228A
(-7750 2550) 0;
DISPLAY LEFT (-7750 2550);
DISPLAY 0.808511 (-7750 2550);
PAINT PURPLE (-7750 2550);
FORCENOTE
CONNECTION
(-2015 1765) 0;
DISPLAY LEFT (-2015 1765);
PAINT PURPLE (-2015 1765);
FORCENOTE
PVCCIN CPU1 VOLTAGE SENSE
(-7340 1315) 0;
DISPLAY LEFT (-7340 1315);
PAINT PURPLE (-7340 1315);
FORCENOTE
SPOF
(-5905 3050) 0;
DISPLAY LEFT (-5905 3050);
DISPLAY 1.936170 (-5905 3050);
PAINT PURPLE (-5905 3050);
FORCENOTE
ROOM = PVCCIN_CPU1_FILTER_VR
(-3690 640) 0;
DISPLAY LEFT (-3690 640);
DISPLAY 2.446809 (-3690 640);
PAINT PURPLE (-3690 640);
FORCENOTE
5MIL SPACING
(-6815 1540) 0;
DISPLAY LEFT (-6815 1540);
DISPLAY 0.808511 (-6815 1540);
PAINT PURPLE (-6815 1540);
FORCENOTE
10MIL WIDTH
(-6790 1615) 0;
DISPLAY LEFT (-6790 1615);
DISPLAY 0.808511 (-6790 1615);
PAINT PURPLE (-6790 1615);
FORCENOTE
ROUT AS DIFF PAIR
(-6915 1690) 0;
DISPLAY LEFT (-6915 1690);
DISPLAY 0.808511 (-6915 1690);
PAINT PURPLE (-6915 1690);
FORCENOTE
LL=0.9MOHM
(-7750 2350) 0;
DISPLAY LEFT (-7750 2350);
DISPLAY 0.808511 (-7750 2350);
PAINT PURPLE (-7750 2350);
FORCENOTE
IOUT TDC=88A
(-7750 2600) 0;
DISPLAY LEFT (-7750 2600);
DISPLAY 0.808511 (-7750 2600);
PAINT PURPLE (-7750 2600);
FORCENOTE
AC + RIPPLE TOL =  +/-22MV
(-7750 2650) 0;
DISPLAY LEFT (-7750 2650);
DISPLAY 0.808511 (-7750 2650);
PAINT PURPLE (-7750 2650);
FORCENOTE
RIPPLE GUIDE= +/- 5MV
(-7750 2750) 0;
DISPLAY LEFT (-7750 2750);
DISPLAY 0.808511 (-7750 2750);
PAINT PURPLE (-7750 2750);
FORCENOTE
DC TOL = +/-17MV
(-7750 2700) 0;
DISPLAY LEFT (-7750 2700);
DISPLAY 0.808511 (-7750 2700);
PAINT PURPLE (-7750 2700);
FORCENOTE
SW FREQ=625 KHZ 
(-7750 2400) 0;
DISPLAY LEFT (-7750 2400);
DISPLAY 0.808511 (-7750 2400);
PAINT PURPLE (-7750 2400);
FORCENOTE
IOUT DI/DT = 778 A/US
(-7750 2450) 0;
DISPLAY LEFT (-7750 2450);
DISPLAY 0.808511 (-7750 2450);
PAINT PURPLE (-7750 2450);
FORCENOTE
IOUT STEP=187 APP
(-7750 2500) 0;
DISPLAY LEFT (-7750 2500);
DISPLAY 0.808511 (-7750 2500);
PAINT PURPLE (-7750 2500);
FORCENOTE
KELVIN
(-1940 1840) 0;
DISPLAY LEFT (-1940 1840);
PAINT PURPLE (-1940 1840);
FORCENOTE
VR CONTROLLER SIDE
(-7940 1690) 0;
DISPLAY LEFT (-7940 1690);
PAINT PURPLE (-7940 1690);
FORCENOTE
VBOOT=0.7V
(-7750 2300) 0;
DISPLAY LEFT (-7750 2300);
DISPLAY 0.808511 (-7750 2300);
PAINT PURPLE (-7750 2300);
FORCENOTE
TP FAB1 CO-LAY WITH TI PARTS 11/16
(-2050 2875) 0;
DISPLAY LEFT (-2050 2875);
DISPLAY 0.851064 (-2050 2875);
PAINT RED (-2050 2875);
FORCENOTE
SOCKET SIDE
(-4815 1690) 0;
DISPLAY LEFT (-4815 1690);
PAINT PURPLE (-4815 1690);
FORCENOTE
TP FAB1 CO-LAY WITH TI PARTS 11/16
(-5150 3100) 0;
DISPLAY LEFT (-5150 3100);
DISPLAY 0.851064 (-5150 3100);
PAINT RED (-5150 3100);
FORCENOTE
TP FAB1 3.01 OHM NEED CHANGE TO 2.2 OHM BUT WAIT FOR SYMBOL
(-2025 2800) 0;
DISPLAY LEFT (-2025 2800);
DISPLAY 0.851064 (-2025 2800);
PAINT RED (-2025 2800);
FORCENOTE
ROOM=PVCCIN_CPU1_PWR_VR
(-3905 2610) 0;
DISPLAY LEFT (-3905 2610);
DISPLAY 2.446809 (-3905 2610);
PAINT PURPLE (-3905 2610);
FORCENOTE
TP FAB1 CO-LAY WITH TI PARTS 11/16
(-1700 3575) 0;
DISPLAY LEFT (-1700 3575);
DISPLAY 0.851064 (-1700 3575);
PAINT RED (-1700 3575);
FORCENOTE
VOUT=1.8V(NOM)
(-7750 2800) 0;
DISPLAY LEFT (-7750 2800);
DISPLAY 0.808511 (-7750 2800);
PAINT PURPLE (-7750 2800);
QUIT
